FILE_TYPE = MACRO_DRAWING;
SET COLOR_WIRE YELLOW;
SET COLOR_PROP ORANGE;
SET COLOR_DOT WHITE;
SET COLOR_ARC YELLOW;
SET COLOR_BODY GREEN;
SET COLOR_NOTE PURPLE;
SET PROP_DISPLAY VALUE;
SET PAGE_NUMBER P42;
FORCEADD GENOA_SP5..6
(-4600 3775);
FORCEPROP 1 LAST LOCATION U26
J 0
(-5245 6606);
DISPLAY 0.489362 (-5245 6606);
PAINT SKYBLUE (-5245 6606);
FORCEPROP 0 LAST $SEC 6
J 0
(-5225 6650);
DISPLAY 0.680851 (-5225 6650);
PAINT MONO (-5225 6650);
DISPLAY INVISIBLE (-5225 6650);
FORCEPROP 0 LAST CDS_SEC 6
J 0
(-5250 6575);
DISPLAY 1.021277 (-5250 6575);
DISPLAY INVISIBLE (-5250 6575);
FORCEPROP 0 LASTPIN (-5400 3150) $PN BC67
J 2
(-5410 3160);
DISPLAY 0.489362 (-5410 3160);
PAINT MONO (-5410 3160);
FORCEPROP 0 LASTPIN (-5400 3100) $PN BD67
J 2
(-5410 3110);
DISPLAY 0.489362 (-5410 3110);
PAINT MONO (-5410 3110);
FORCEPROP 0 LASTPIN (-5400 2000) $PN BF67
J 2
(-5410 2010);
DISPLAY 0.489362 (-5410 2010);
PAINT MONO (-5410 2010);
FORCEPROP 0 LASTPIN (-5400 1950) $PN BG67
J 2
(-5410 1960);
DISPLAY 0.489362 (-5410 1960);
PAINT MONO (-5410 1960);
FORCEPROP 0 LASTPIN (-5400 2300) $PN AT65
J 2
(-5410 2310);
DISPLAY 0.489362 (-5410 2310);
PAINT MONO (-5410 2310);
FORCEPROP 0 LASTPIN (-5400 2200) $PN AU66
J 2
(-5410 2210);
DISPLAY 0.489362 (-5410 2210);
PAINT MONO (-5410 2210);
FORCEPROP 0 LASTPIN (-5400 3000) $PN AV67
J 2
(-5410 3010);
DISPLAY 0.489362 (-5410 3010);
PAINT MONO (-5410 3010);
FORCEPROP 0 LASTPIN (-5400 2950) $PN AW66
J 2
(-5410 2960);
DISPLAY 0.489362 (-5410 2960);
PAINT MONO (-5410 2960);
FORCEPROP 0 LASTPIN (-5400 2850) $PN BN66
J 2
(-5410 2860);
DISPLAY 0.489362 (-5410 2860);
PAINT MONO (-5410 2860);
FORCEPROP 0 LASTPIN (-5400 1850) $PN AU67
J 2
(-5410 1860);
DISPLAY 0.489362 (-5410 1860);
PAINT MONO (-5410 1860);
FORCEPROP 0 LASTPIN (-5400 1800) $PN AV65
J 2
(-5410 1810);
DISPLAY 0.489362 (-5410 1810);
PAINT MONO (-5410 1810);
FORCEPROP 0 LASTPIN (-5400 1700) $PN BP65
J 2
(-5410 1710);
DISPLAY 0.489362 (-5410 1710);
PAINT MONO (-5410 1710);
FORCEPROP 0 LASTPIN (-5400 4000) $PN AW67
J 2
(-5410 4010);
DISPLAY 0.489362 (-5410 4010);
PAINT MONO (-5410 4010);
FORCEPROP 0 LASTPIN (-5400 3950) $PN AY67
J 2
(-5410 3960);
DISPLAY 0.489362 (-5410 3960);
PAINT MONO (-5410 3960);
FORCEPROP 0 LASTPIN (-5400 3900) $PN AY65
J 2
(-5410 3910);
DISPLAY 0.489362 (-5410 3910);
PAINT MONO (-5410 3910);
FORCEPROP 0 LASTPIN (-5400 3850) $PN BA66
J 2
(-5410 3860);
DISPLAY 0.489362 (-5410 3860);
PAINT MONO (-5410 3860);
FORCEPROP 0 LASTPIN (-5400 3800) $PN BA67
J 2
(-5410 3810);
DISPLAY 0.489362 (-5410 3810);
PAINT MONO (-5410 3810);
FORCEPROP 0 LASTPIN (-5400 3750) $PN BB67
J 2
(-5410 3760);
DISPLAY 0.489362 (-5410 3760);
PAINT MONO (-5410 3760);
FORCEPROP 0 LASTPIN (-5400 3700) $PN BB65
J 2
(-5410 3710);
DISPLAY 0.489362 (-5410 3710);
PAINT MONO (-5410 3710);
FORCEPROP 0 LASTPIN (-3800 2550) $PN AJ67
J 0
(-3790 2560);
DISPLAY 0.489362 (-3790 2560);
PAINT MONO (-3790 2560);
FORCEPROP 0 LASTPIN (-3800 2500) $PN AK65
J 0
(-3790 2510);
DISPLAY 0.489362 (-3790 2510);
PAINT MONO (-3790 2510);
FORCEPROP 0 LASTPIN (-3800 2450) $PN AK67
J 0
(-3790 2460);
DISPLAY 0.489362 (-3790 2460);
PAINT MONO (-3790 2460);
FORCEPROP 0 LASTPIN (-3800 2400) $PN AL66
J 0
(-3790 2410);
DISPLAY 0.489362 (-3790 2410);
PAINT MONO (-3790 2410);
FORCEPROP 0 LASTPIN (-3800 2350) $PN AN67
J 0
(-3790 2360);
DISPLAY 0.489362 (-3790 2360);
PAINT MONO (-3790 2360);
FORCEPROP 0 LASTPIN (-3800 2300) $PN AP65
J 0
(-3790 2310);
DISPLAY 0.489362 (-3790 2310);
PAINT MONO (-3790 2310);
FORCEPROP 0 LASTPIN (-3800 2250) $PN AP67
J 0
(-3790 2260);
DISPLAY 0.489362 (-3790 2260);
PAINT MONO (-3790 2260);
FORCEPROP 0 LASTPIN (-3800 2200) $PN AR66
J 0
(-3790 2210);
DISPLAY 0.489362 (-3790 2210);
PAINT MONO (-3790 2210);
FORCEPROP 0 LASTPIN (-3800 6150) $PN E67
J 0
(-3790 6160);
DISPLAY 0.489362 (-3790 6160);
PAINT MONO (-3790 6160);
FORCEPROP 0 LASTPIN (-3800 6100) $PN F65
J 0
(-3790 6110);
DISPLAY 0.489362 (-3790 6110);
PAINT MONO (-3790 6110);
FORCEPROP 0 LASTPIN (-3800 6050) $PN F67
J 0
(-3790 6060);
DISPLAY 0.489362 (-3790 6060);
PAINT MONO (-3790 6060);
FORCEPROP 0 LASTPIN (-3800 6000) $PN G66
J 0
(-3790 6010);
DISPLAY 0.489362 (-3790 6010);
PAINT MONO (-3790 6010);
FORCEPROP 0 LASTPIN (-3800 5950) $PN J67
J 0
(-3790 5960);
DISPLAY 0.489362 (-3790 5960);
PAINT MONO (-3790 5960);
FORCEPROP 0 LASTPIN (-3800 5900) $PN K65
J 0
(-3790 5910);
DISPLAY 0.489362 (-3790 5910);
PAINT MONO (-3790 5910);
FORCEPROP 0 LASTPIN (-3800 5850) $PN K67
J 0
(-3790 5860);
DISPLAY 0.489362 (-3790 5860);
PAINT MONO (-3790 5860);
FORCEPROP 0 LASTPIN (-3800 5800) $PN L66
J 0
(-3790 5810);
DISPLAY 0.489362 (-3790 5810);
PAINT MONO (-3790 5810);
FORCEPROP 0 LASTPIN (-3800 5700) $PN L67
J 0
(-3790 5710);
DISPLAY 0.489362 (-3790 5710);
PAINT MONO (-3790 5710);
FORCEPROP 0 LASTPIN (-3800 5650) $PN M65
J 0
(-3790 5660);
DISPLAY 0.489362 (-3790 5660);
PAINT MONO (-3790 5660);
FORCEPROP 0 LASTPIN (-3800 5600) $PN M67
J 0
(-3790 5610);
DISPLAY 0.489362 (-3790 5610);
PAINT MONO (-3790 5610);
FORCEPROP 0 LASTPIN (-3800 5550) $PN N66
J 0
(-3790 5560);
DISPLAY 0.489362 (-3790 5560);
PAINT MONO (-3790 5560);
FORCEPROP 0 LASTPIN (-3800 5500) $PN R67
J 0
(-3790 5510);
DISPLAY 0.489362 (-3790 5510);
PAINT MONO (-3790 5510);
FORCEPROP 0 LASTPIN (-3800 5450) $PN T65
J 0
(-3790 5460);
DISPLAY 0.489362 (-3790 5460);
PAINT MONO (-3790 5460);
FORCEPROP 0 LASTPIN (-3800 5400) $PN T67
J 0
(-3790 5410);
DISPLAY 0.489362 (-3790 5410);
PAINT MONO (-3790 5410);
FORCEPROP 0 LASTPIN (-3800 5350) $PN U66
J 0
(-3790 5360);
DISPLAY 0.489362 (-3790 5360);
PAINT MONO (-3790 5360);
FORCEPROP 0 LASTPIN (-3800 5250) $PN U67
J 0
(-3790 5260);
DISPLAY 0.489362 (-3790 5260);
PAINT MONO (-3790 5260);
FORCEPROP 0 LASTPIN (-3800 5200) $PN V65
J 0
(-3790 5210);
DISPLAY 0.489362 (-3790 5210);
PAINT MONO (-3790 5210);
FORCEPROP 0 LASTPIN (-3800 5150) $PN V67
J 0
(-3790 5160);
DISPLAY 0.489362 (-3790 5160);
PAINT MONO (-3790 5160);
FORCEPROP 0 LASTPIN (-3800 5100) $PN W66
J 0
(-3790 5110);
DISPLAY 0.489362 (-3790 5110);
PAINT MONO (-3790 5110);
FORCEPROP 0 LASTPIN (-3800 5050) $PN AA67
J 0
(-3790 5060);
DISPLAY 0.489362 (-3790 5060);
PAINT MONO (-3790 5060);
FORCEPROP 0 LASTPIN (-3800 5000) $PN AB65
J 0
(-3790 5010);
DISPLAY 0.489362 (-3790 5010);
PAINT MONO (-3790 5010);
FORCEPROP 0 LASTPIN (-3800 4950) $PN AB67
J 0
(-3790 4960);
DISPLAY 0.489362 (-3790 4960);
PAINT MONO (-3790 4960);
FORCEPROP 0 LASTPIN (-3800 4900) $PN AC66
J 0
(-3790 4910);
DISPLAY 0.489362 (-3790 4910);
PAINT MONO (-3790 4910);
FORCEPROP 0 LASTPIN (-3800 4800) $PN AC67
J 0
(-3790 4810);
DISPLAY 0.489362 (-3790 4810);
PAINT MONO (-3790 4810);
FORCEPROP 0 LASTPIN (-3800 4750) $PN AD65
J 0
(-3790 4760);
DISPLAY 0.489362 (-3790 4760);
PAINT MONO (-3790 4760);
FORCEPROP 0 LASTPIN (-3800 4700) $PN AD67
J 0
(-3790 4710);
DISPLAY 0.489362 (-3790 4710);
PAINT MONO (-3790 4710);
FORCEPROP 0 LASTPIN (-3800 4650) $PN AE66
J 0
(-3790 4660);
DISPLAY 0.489362 (-3790 4660);
PAINT MONO (-3790 4660);
FORCEPROP 0 LASTPIN (-3800 4600) $PN AG67
J 0
(-3790 4610);
DISPLAY 0.489362 (-3790 4610);
PAINT MONO (-3790 4610);
FORCEPROP 0 LASTPIN (-3800 4550) $PN AH65
J 0
(-3790 4560);
DISPLAY 0.489362 (-3790 4560);
PAINT MONO (-3790 4560);
FORCEPROP 0 LASTPIN (-3800 4500) $PN AH67
J 0
(-3790 4510);
DISPLAY 0.489362 (-3790 4510);
PAINT MONO (-3790 4510);
FORCEPROP 0 LASTPIN (-3800 4450) $PN AJ66
J 0
(-3790 4460);
DISPLAY 0.489362 (-3790 4460);
PAINT MONO (-3790 4460);
FORCEPROP 0 LASTPIN (-5400 6150) $PN G67
J 2
(-5410 6160);
DISPLAY 0.489362 (-5410 6160);
PAINT MONO (-5410 6160);
FORCEPROP 0 LASTPIN (-5400 6050) $PN N67
J 2
(-5410 6060);
DISPLAY 0.489362 (-5410 6060);
PAINT MONO (-5410 6060);
FORCEPROP 0 LASTPIN (-5400 5950) $PN W67
J 2
(-5410 5960);
DISPLAY 0.489362 (-5410 5960);
PAINT MONO (-5410 5960);
FORCEPROP 0 LASTPIN (-5400 5850) $PN AE67
J 2
(-5410 5860);
DISPLAY 0.489362 (-5410 5860);
PAINT MONO (-5410 5860);
FORCEPROP 0 LASTPIN (-5400 5750) $PN AL67
J 2
(-5410 5760);
DISPLAY 0.489362 (-5410 5760);
PAINT MONO (-5410 5760);
FORCEPROP 0 LASTPIN (-5400 5650) $PN J66
J 2
(-5410 5660);
DISPLAY 0.489362 (-5410 5660);
PAINT MONO (-5410 5660);
FORCEPROP 0 LASTPIN (-5400 5550) $PN R66
J 2
(-5410 5560);
DISPLAY 0.489362 (-5410 5560);
PAINT MONO (-5410 5560);
FORCEPROP 0 LASTPIN (-5400 5450) $PN AA66
J 2
(-5410 5460);
DISPLAY 0.489362 (-5410 5460);
PAINT MONO (-5410 5460);
FORCEPROP 0 LASTPIN (-5400 5350) $PN AG66
J 2
(-5410 5360);
DISPLAY 0.489362 (-5410 5360);
PAINT MONO (-5410 5360);
FORCEPROP 0 LASTPIN (-5400 5250) $PN AN66
J 2
(-5410 5260);
DISPLAY 0.489362 (-5410 5260);
PAINT MONO (-5410 5260);
FORCEPROP 0 LASTPIN (-5400 6100) $PN H67
J 2
(-5410 6110);
DISPLAY 0.489362 (-5410 6110);
PAINT MONO (-5410 6110);
FORCEPROP 0 LASTPIN (-5400 6000) $PN P67
J 2
(-5410 6010);
DISPLAY 0.489362 (-5410 6010);
PAINT MONO (-5410 6010);
FORCEPROP 0 LASTPIN (-5400 5900) $PN Y67
J 2
(-5410 5910);
DISPLAY 0.489362 (-5410 5910);
PAINT MONO (-5410 5910);
FORCEPROP 0 LASTPIN (-5400 5800) $PN AF67
J 2
(-5410 5810);
DISPLAY 0.489362 (-5410 5810);
PAINT MONO (-5410 5810);
FORCEPROP 0 LASTPIN (-5400 5700) $PN AM67
J 2
(-5410 5710);
DISPLAY 0.489362 (-5410 5710);
PAINT MONO (-5410 5710);
FORCEPROP 0 LASTPIN (-5400 5600) $PN H65
J 2
(-5410 5610);
DISPLAY 0.489362 (-5410 5610);
PAINT MONO (-5410 5610);
FORCEPROP 0 LASTPIN (-5400 5500) $PN P65
J 2
(-5410 5510);
DISPLAY 0.489362 (-5410 5510);
PAINT MONO (-5410 5510);
FORCEPROP 0 LASTPIN (-5400 5400) $PN Y65
J 2
(-5410 5410);
DISPLAY 0.489362 (-5410 5410);
PAINT MONO (-5410 5410);
FORCEPROP 0 LASTPIN (-5400 5300) $PN AF65
J 2
(-5410 5310);
DISPLAY 0.489362 (-5410 5310);
PAINT MONO (-5410 5310);
FORCEPROP 0 LASTPIN (-5400 5200) $PN AM65
J 2
(-5410 5210);
DISPLAY 0.489362 (-5410 5210);
PAINT MONO (-5410 5210);
FORCEPROP 0 LASTPIN (-5400 2750) $PN BC66
J 2
(-5410 2760);
DISPLAY 0.489362 (-5410 2760);
PAINT MONO (-5410 2760);
FORCEPROP 0 LASTPIN (-5400 2650) $PN BM65
J 2
(-5410 2660);
DISPLAY 0.489362 (-5410 2660);
PAINT MONO (-5410 2660);
FORCEPROP 0 LASTPIN (-5400 2600) $PN BN67
J 2
(-5410 2610);
DISPLAY 0.489362 (-5410 2610);
PAINT MONO (-5410 2610);
FORCEPROP 0 LASTPIN (-5400 2500) $PN BP67
J 2
(-5410 2510);
DISPLAY 0.489362 (-5410 2510);
PAINT MONO (-5410 2510);
FORCEPROP 0 LASTPIN (-5400 1600) $PN BL66
J 2
(-5410 1610);
DISPLAY 0.489362 (-5410 1610);
PAINT MONO (-5410 1610);
FORCEPROP 0 LASTPIN (-5400 1550) $PN BM67
J 2
(-5410 1560);
DISPLAY 0.489362 (-5410 1560);
PAINT MONO (-5410 1560);
FORCEPROP 0 LASTPIN (-5400 1450) $PN BR67
J 2
(-5410 1460);
DISPLAY 0.489362 (-5410 1460);
PAINT MONO (-5410 1460);
FORCEPROP 0 LASTPIN (-5400 3600) $PN BG66
J 2
(-5410 3610);
DISPLAY 0.489362 (-5410 3610);
PAINT MONO (-5410 3610);
FORCEPROP 0 LASTPIN (-5400 3550) $PN BH65
J 2
(-5410 3560);
DISPLAY 0.489362 (-5410 3560);
PAINT MONO (-5410 3560);
FORCEPROP 0 LASTPIN (-5400 3500) $PN BH67
J 2
(-5410 3510);
DISPLAY 0.489362 (-5410 3510);
PAINT MONO (-5410 3510);
FORCEPROP 0 LASTPIN (-5400 3450) $PN BJ67
J 2
(-5410 3460);
DISPLAY 0.489362 (-5410 3460);
PAINT MONO (-5410 3460);
FORCEPROP 0 LASTPIN (-5400 3400) $PN BJ66
J 2
(-5410 3410);
DISPLAY 0.489362 (-5410 3410);
PAINT MONO (-5410 3410);
FORCEPROP 0 LASTPIN (-5400 3350) $PN BK65
J 2
(-5410 3360);
DISPLAY 0.489362 (-5410 3360);
PAINT MONO (-5410 3360);
FORCEPROP 0 LASTPIN (-5400 3300) $PN BK67
J 2
(-5410 3310);
DISPLAY 0.489362 (-5410 3310);
PAINT MONO (-5410 3310);
FORCEPROP 0 LASTPIN (-3800 2100) $PN BY67
J 0
(-3790 2110);
DISPLAY 0.489362 (-3790 2110);
PAINT MONO (-3790 2110);
FORCEPROP 0 LASTPIN (-3800 2050) $PN CA66
J 0
(-3790 2060);
DISPLAY 0.489362 (-3790 2060);
PAINT MONO (-3790 2060);
FORCEPROP 0 LASTPIN (-3800 2000) $PN CA67
J 0
(-3790 2010);
DISPLAY 0.489362 (-3790 2010);
PAINT MONO (-3790 2010);
FORCEPROP 0 LASTPIN (-3800 1950) $PN CB65
J 0
(-3790 1960);
DISPLAY 0.489362 (-3790 1960);
PAINT MONO (-3790 1960);
FORCEPROP 0 LASTPIN (-3800 1900) $PN BT67
J 0
(-3790 1910);
DISPLAY 0.489362 (-3790 1910);
PAINT MONO (-3790 1910);
FORCEPROP 0 LASTPIN (-3800 1850) $PN BU66
J 0
(-3790 1860);
DISPLAY 0.489362 (-3790 1860);
PAINT MONO (-3790 1860);
FORCEPROP 0 LASTPIN (-3800 1800) $PN BU67
J 0
(-3790 1810);
DISPLAY 0.489362 (-3790 1810);
PAINT MONO (-3790 1810);
FORCEPROP 0 LASTPIN (-3800 1750) $PN BV65
J 0
(-3790 1760);
DISPLAY 0.489362 (-3790 1760);
PAINT MONO (-3790 1760);
FORCEPROP 0 LASTPIN (-3800 4350) $PN CB67
J 0
(-3790 4360);
DISPLAY 0.489362 (-3790 4360);
PAINT MONO (-3790 4360);
FORCEPROP 0 LASTPIN (-3800 4300) $PN CC66
J 0
(-3790 4310);
DISPLAY 0.489362 (-3790 4310);
PAINT MONO (-3790 4310);
FORCEPROP 0 LASTPIN (-3800 4250) $PN CC67
J 0
(-3790 4260);
DISPLAY 0.489362 (-3790 4260);
PAINT MONO (-3790 4260);
FORCEPROP 0 LASTPIN (-3800 4200) $PN CD65
J 0
(-3790 4210);
DISPLAY 0.489362 (-3790 4210);
PAINT MONO (-3790 4210);
FORCEPROP 0 LASTPIN (-3800 4150) $PN CF67
J 0
(-3790 4160);
DISPLAY 0.489362 (-3790 4160);
PAINT MONO (-3790 4160);
FORCEPROP 0 LASTPIN (-3800 4100) $PN CG66
J 0
(-3790 4110);
DISPLAY 0.489362 (-3790 4110);
PAINT MONO (-3790 4110);
FORCEPROP 0 LASTPIN (-3800 4050) $PN CG67
J 0
(-3790 4060);
DISPLAY 0.489362 (-3790 4060);
PAINT MONO (-3790 4060);
FORCEPROP 0 LASTPIN (-3800 4000) $PN CH65
J 0
(-3790 4010);
DISPLAY 0.489362 (-3790 4010);
PAINT MONO (-3790 4010);
FORCEPROP 0 LASTPIN (-3800 3900) $PN CH67
J 0
(-3790 3910);
DISPLAY 0.489362 (-3790 3910);
PAINT MONO (-3790 3910);
FORCEPROP 0 LASTPIN (-3800 3850) $PN CJ66
J 0
(-3790 3860);
DISPLAY 0.489362 (-3790 3860);
PAINT MONO (-3790 3860);
FORCEPROP 0 LASTPIN (-3800 3800) $PN CJ67
J 0
(-3790 3810);
DISPLAY 0.489362 (-3790 3810);
PAINT MONO (-3790 3810);
FORCEPROP 0 LASTPIN (-3800 3750) $PN CK65
J 0
(-3790 3760);
DISPLAY 0.489362 (-3790 3760);
PAINT MONO (-3790 3760);
FORCEPROP 0 LASTPIN (-3800 3700) $PN CM67
J 0
(-3790 3710);
DISPLAY 0.489362 (-3790 3710);
PAINT MONO (-3790 3710);
FORCEPROP 0 LASTPIN (-3800 3650) $PN CN66
J 0
(-3790 3660);
DISPLAY 0.489362 (-3790 3660);
PAINT MONO (-3790 3660);
FORCEPROP 0 LASTPIN (-3800 3600) $PN CN67
J 0
(-3790 3610);
DISPLAY 0.489362 (-3790 3610);
PAINT MONO (-3790 3610);
FORCEPROP 0 LASTPIN (-3800 3550) $PN CP65
J 0
(-3790 3560);
DISPLAY 0.489362 (-3790 3560);
PAINT MONO (-3790 3560);
FORCEPROP 0 LASTPIN (-3800 3450) $PN CP67
J 0
(-3790 3460);
DISPLAY 0.489362 (-3790 3460);
PAINT MONO (-3790 3460);
FORCEPROP 0 LASTPIN (-3800 3400) $PN CR66
J 0
(-3790 3410);
DISPLAY 0.489362 (-3790 3410);
PAINT MONO (-3790 3410);
FORCEPROP 0 LASTPIN (-3800 3350) $PN CR67
J 0
(-3790 3360);
DISPLAY 0.489362 (-3790 3360);
PAINT MONO (-3790 3360);
FORCEPROP 0 LASTPIN (-3800 3300) $PN CT65
J 0
(-3790 3310);
DISPLAY 0.489362 (-3790 3310);
PAINT MONO (-3790 3310);
FORCEPROP 0 LASTPIN (-3800 3250) $PN CV67
J 0
(-3790 3260);
DISPLAY 0.489362 (-3790 3260);
PAINT MONO (-3790 3260);
FORCEPROP 0 LASTPIN (-3800 3200) $PN CW66
J 0
(-3790 3210);
DISPLAY 0.489362 (-3790 3210);
PAINT MONO (-3790 3210);
FORCEPROP 0 LASTPIN (-3800 3150) $PN CW67
J 0
(-3790 3160);
DISPLAY 0.489362 (-3790 3160);
PAINT MONO (-3790 3160);
FORCEPROP 0 LASTPIN (-3800 3100) $PN CY65
J 0
(-3790 3110);
DISPLAY 0.489362 (-3790 3110);
PAINT MONO (-3790 3110);
FORCEPROP 0 LASTPIN (-3800 3000) $PN CY67
J 0
(-3790 3010);
DISPLAY 0.489362 (-3790 3010);
PAINT MONO (-3790 3010);
FORCEPROP 0 LASTPIN (-3800 2950) $PN DA66
J 0
(-3790 2960);
DISPLAY 0.489362 (-3790 2960);
PAINT MONO (-3790 2960);
FORCEPROP 0 LASTPIN (-3800 2900) $PN DA67
J 0
(-3790 2910);
DISPLAY 0.489362 (-3790 2910);
PAINT MONO (-3790 2910);
FORCEPROP 0 LASTPIN (-3800 2850) $PN DB65
J 0
(-3790 2860);
DISPLAY 0.489362 (-3790 2860);
PAINT MONO (-3790 2860);
FORCEPROP 0 LASTPIN (-3800 2800) $PN DD67
J 0
(-3790 2810);
DISPLAY 0.489362 (-3790 2810);
PAINT MONO (-3790 2810);
FORCEPROP 0 LASTPIN (-3800 2750) $PN DE66
J 0
(-3790 2760);
DISPLAY 0.489362 (-3790 2760);
PAINT MONO (-3790 2760);
FORCEPROP 0 LASTPIN (-3800 2700) $PN DE67
J 0
(-3790 2710);
DISPLAY 0.489362 (-3790 2710);
PAINT MONO (-3790 2710);
FORCEPROP 0 LASTPIN (-3800 2650) $PN DF67
J 0
(-3790 2660);
DISPLAY 0.489362 (-3790 2660);
PAINT MONO (-3790 2660);
FORCEPROP 0 LASTPIN (-5400 5100) $PN CD67
J 2
(-5410 5110);
DISPLAY 0.489362 (-5410 5110);
PAINT MONO (-5410 5110);
FORCEPROP 0 LASTPIN (-5400 5000) $PN CK67
J 2
(-5410 5010);
DISPLAY 0.489362 (-5410 5010);
PAINT MONO (-5410 5010);
FORCEPROP 0 LASTPIN (-5400 4900) $PN CT67
J 2
(-5410 4910);
DISPLAY 0.489362 (-5410 4910);
PAINT MONO (-5410 4910);
FORCEPROP 0 LASTPIN (-5400 4800) $PN DB67
J 2
(-5410 4810);
DISPLAY 0.489362 (-5410 4810);
PAINT MONO (-5410 4810);
FORCEPROP 0 LASTPIN (-5400 4700) $PN BY65
J 2
(-5410 4710);
DISPLAY 0.489362 (-5410 4710);
PAINT MONO (-5410 4710);
FORCEPROP 0 LASTPIN (-5400 4600) $PN CF65
J 2
(-5410 4610);
DISPLAY 0.489362 (-5410 4610);
PAINT MONO (-5410 4610);
FORCEPROP 0 LASTPIN (-5400 4500) $PN CM65
J 2
(-5410 4510);
DISPLAY 0.489362 (-5410 4510);
PAINT MONO (-5410 4510);
FORCEPROP 0 LASTPIN (-5400 4400) $PN CV65
J 2
(-5410 4410);
DISPLAY 0.489362 (-5410 4410);
PAINT MONO (-5410 4410);
FORCEPROP 0 LASTPIN (-5400 4300) $PN DD65
J 2
(-5410 4310);
DISPLAY 0.489362 (-5410 4310);
PAINT MONO (-5410 4310);
FORCEPROP 0 LASTPIN (-5400 4200) $PN BV67
J 2
(-5410 4210);
DISPLAY 0.489362 (-5410 4210);
PAINT MONO (-5410 4210);
FORCEPROP 0 LASTPIN (-5400 5050) $PN CE67
J 2
(-5410 5060);
DISPLAY 0.489362 (-5410 5060);
PAINT MONO (-5410 5060);
FORCEPROP 0 LASTPIN (-5400 4950) $PN CL67
J 2
(-5410 4960);
DISPLAY 0.489362 (-5410 4960);
PAINT MONO (-5410 4960);
FORCEPROP 0 LASTPIN (-5400 4850) $PN CU67
J 2
(-5410 4860);
DISPLAY 0.489362 (-5410 4860);
PAINT MONO (-5410 4860);
FORCEPROP 0 LASTPIN (-5400 4750) $PN DC67
J 2
(-5410 4760);
DISPLAY 0.489362 (-5410 4760);
PAINT MONO (-5410 4760);
FORCEPROP 0 LASTPIN (-5400 4650) $PN BW66
J 2
(-5410 4660);
DISPLAY 0.489362 (-5410 4660);
PAINT MONO (-5410 4660);
FORCEPROP 0 LASTPIN (-5400 4550) $PN CE66
J 2
(-5410 4560);
DISPLAY 0.489362 (-5410 4560);
PAINT MONO (-5410 4560);
FORCEPROP 0 LASTPIN (-5400 4450) $PN CL66
J 2
(-5410 4460);
DISPLAY 0.489362 (-5410 4460);
PAINT MONO (-5410 4460);
FORCEPROP 0 LASTPIN (-5400 4350) $PN CU66
J 2
(-5410 4360);
DISPLAY 0.489362 (-5410 4360);
PAINT MONO (-5410 4360);
FORCEPROP 0 LASTPIN (-5400 4250) $PN DC66
J 2
(-5410 4260);
DISPLAY 0.489362 (-5410 4260);
PAINT MONO (-5410 4260);
FORCEPROP 0 LASTPIN (-5400 4150) $PN BW67
J 2
(-5410 4160);
DISPLAY 0.489362 (-5410 4160);
PAINT MONO (-5410 4160);
FORCEPROP 0 LASTPIN (-5400 2400) $PN BL67
J 2
(-5410 2410);
DISPLAY 0.489362 (-5410 2410);
PAINT MONO (-5410 2410);
FORCEPROP 0 LASTPIN (-5400 1350) $PN BF65
J 2
(-5410 1360);
DISPLAY 0.489362 (-5410 1360);
PAINT MONO (-5410 1360);
FORCEPROP 2 LAST PART_TYPE SMLF
J 0
(-5250 6525);
DISPLAY 1.021277 (-5250 6525);
FORCEPROP 1 LAST MATERIAL IO
J 0
(-5245 6332);
DISPLAY 0.489362 (-5245 6332);
PAINT SKYBLUE (-5245 6332);
FORCEPROP 2 LAST VALUE SOCKET6096_13568-001
J 0
(-5250 6425);
DISPLAY 0.489362 (-5250 6425);
PAINT SKYBLUE (-5250 6425);
FORCEPROP 2 LAST CDS_LIB pure_quanta
J 0
(-4600 3775);
DISPLAY INVISIBLE (-4600 3775);
FORCEPROP 1 LAST CDS_LMAN_SYM_OUTLINE -650,2525,650,-2525
J 0
(-4600 3775);
DISPLAY 0.468085 (-4600 3775);
PAINT GREEN (-4600 3775);
DISPLAY INVISIBLE (-4600 3775);
FORCEPROP 1 LAST NEEDS_NO_SIZE TRUE
J 0
(-4600 3775);
DISPLAY 0.723404 (-4600 3775);
PAINT GREEN (-4600 3775);
DISPLAY INVISIBLE (-4600 3775);
FORCEPROP 1 LAST PATH I159
J 0
(-4600 3775);
DISPLAY 0.723404 (-4600 3775);
PAINT GREEN (-4600 3775);
DISPLAY INVISIBLE (-4600 3775);
FORCEPROP 1 LAST PART_NUMBER DGA^6000030
J 0
(-5245 6459);
DISPLAY 0.489362 (-5245 6459);
PAINT SKYBLUE (-5245 6459);
DISPLAY INVISIBLE (-5245 6459);
FORCEADD TAP..1
(-3325 6150);
FORCEPROP 3 LASTPIN (-3375 6150) SIG_NAME M_F_CPU1_SA_DQ<0>
J 0
(-3365 6160);
DISPLAY 0.659574 (-3365 6160);
PAINT MONO (-3365 6160);
DISPLAY INVISIBLE (-3365 6160);
FORCEPROP 1 LASTPIN (-3375 6150) BN 0
J 0
(-3387 6158);
DISPLAY 0.489362 (-3387 6158);
PAINT GREEN (-3387 6158);
FORCEPROP 2 LAST CDS_LIB mstr_standard
J 0
(-3325 6150);
DISPLAY 0.723404 (-3325 6150);
PAINT MONO (-3325 6150);
DISPLAY INVISIBLE (-3325 6150);
FORCEPROP 1 LAST BODY_TYPE PLUMBING
J 0
(-3325 6200);
DISPLAY 0.872340 (-3325 6200);
PAINT GREEN (-3325 6200);
DISPLAY INVISIBLE (-3325 6200);
FORCEPROP 1 LAST HDL_TAP TRUE
J 0
(-3000 6025);
DISPLAY 0.872340 (-3000 6025);
DISPLAY INVISIBLE (-3000 6025);
FORCEPROP 1 LAST PATH I160
J 0
(-3327 6150);
DISPLAY 0.872340 (-3327 6150);
PAINT GREEN (-3327 6150);
DISPLAY INVISIBLE (-3327 6150);
FORCEADD OFFPAGE..3
(-2600 6175);
FORCEPROP 2 LAST $XR0 103 
J 0
(-2386 6175);
DISPLAY 0.638298 (-2386 6175);
PAINT MONO (-2386 6175);
FORCEPROP 2 LAST CDS_LIB mstr_standard
J 0
(-2600 6175);
DISPLAY 0.723404 (-2600 6175);
PAINT MONO (-2600 6175);
DISPLAY INVISIBLE (-2600 6175);
FORCEPROP 1 LAST OFFPAGE TRUE
J 0
(-2275 6050);
DISPLAY 0.872340 (-2275 6050);
PAINT GREEN (-2275 6050);
DISPLAY INVISIBLE (-2275 6050);
FORCEPROP 1 LAST COMMENT_BODY TRUE
J 0
(-2650 6075);
DISPLAY 0.872340 (-2650 6075);
PAINT GREEN (-2650 6075);
DISPLAY INVISIBLE (-2650 6075);
FORCEPROP 2 LAST PATH I161
J 0
(-2375 6225);
DISPLAY 1.021277 (-2375 6225);
DISPLAY INVISIBLE (-2375 6225);
FORCEADD OFFPAGE..3
(-2600 4375);
FORCEPROP 2 LAST $XR0 103 
J 0
(-2386 4375);
DISPLAY 0.638298 (-2386 4375);
PAINT MONO (-2386 4375);
FORCEPROP 2 LAST CDS_LIB mstr_standard
J 0
(-2600 4375);
DISPLAY 0.723404 (-2600 4375);
PAINT MONO (-2600 4375);
DISPLAY INVISIBLE (-2600 4375);
FORCEPROP 1 LAST OFFPAGE TRUE
J 0
(-2275 4250);
DISPLAY 0.872340 (-2275 4250);
PAINT GREEN (-2275 4250);
DISPLAY INVISIBLE (-2275 4250);
FORCEPROP 1 LAST COMMENT_BODY TRUE
J 0
(-2650 4275);
DISPLAY 0.872340 (-2650 4275);
PAINT GREEN (-2650 4275);
DISPLAY INVISIBLE (-2650 4275);
FORCEPROP 2 LAST PATH I162
J 0
(-2375 4425);
DISPLAY 1.021277 (-2375 4425);
DISPLAY INVISIBLE (-2375 4425);
FORCEADD TAP..1
(-3325 6100);
FORCEPROP 3 LASTPIN (-3375 6100) SIG_NAME M_F_CPU1_SA_DQ<1>
J 0
(-3365 6110);
DISPLAY 0.659574 (-3365 6110);
PAINT MONO (-3365 6110);
DISPLAY INVISIBLE (-3365 6110);
FORCEPROP 1 LASTPIN (-3375 6100) BN 1
J 0
(-3387 6108);
DISPLAY 0.489362 (-3387 6108);
PAINT GREEN (-3387 6108);
FORCEPROP 2 LAST CDS_LIB mstr_standard
J 0
(-3325 6100);
DISPLAY 0.723404 (-3325 6100);
PAINT MONO (-3325 6100);
DISPLAY INVISIBLE (-3325 6100);
FORCEPROP 1 LAST BODY_TYPE PLUMBING
J 0
(-3325 6150);
DISPLAY 0.872340 (-3325 6150);
PAINT GREEN (-3325 6150);
DISPLAY INVISIBLE (-3325 6150);
FORCEPROP 1 LAST HDL_TAP TRUE
J 0
(-3000 5975);
DISPLAY 0.872340 (-3000 5975);
DISPLAY INVISIBLE (-3000 5975);
FORCEPROP 1 LAST PATH I163
J 0
(-3327 6100);
DISPLAY 0.872340 (-3327 6100);
PAINT GREEN (-3327 6100);
DISPLAY INVISIBLE (-3327 6100);
FORCEADD TAP..1
(-3325 6050);
FORCEPROP 3 LASTPIN (-3375 6050) SIG_NAME M_F_CPU1_SA_DQ<2>
J 0
(-3365 6060);
DISPLAY 0.659574 (-3365 6060);
PAINT MONO (-3365 6060);
DISPLAY INVISIBLE (-3365 6060);
FORCEPROP 1 LASTPIN (-3375 6050) BN 2
J 0
(-3387 6058);
DISPLAY 0.489362 (-3387 6058);
PAINT GREEN (-3387 6058);
FORCEPROP 2 LAST CDS_LIB mstr_standard
J 0
(-3325 6050);
DISPLAY 0.723404 (-3325 6050);
PAINT MONO (-3325 6050);
DISPLAY INVISIBLE (-3325 6050);
FORCEPROP 1 LAST BODY_TYPE PLUMBING
J 0
(-3325 6100);
DISPLAY 0.872340 (-3325 6100);
PAINT GREEN (-3325 6100);
DISPLAY INVISIBLE (-3325 6100);
FORCEPROP 1 LAST HDL_TAP TRUE
J 0
(-3000 5925);
DISPLAY 0.872340 (-3000 5925);
DISPLAY INVISIBLE (-3000 5925);
FORCEPROP 1 LAST PATH I164
J 0
(-3327 6050);
DISPLAY 0.872340 (-3327 6050);
PAINT GREEN (-3327 6050);
DISPLAY INVISIBLE (-3327 6050);
FORCEADD TAP..1
(-3325 5900);
FORCEPROP 3 LASTPIN (-3375 5900) SIG_NAME M_F_CPU1_SA_DQ<5>
J 0
(-3365 5910);
DISPLAY 0.659574 (-3365 5910);
PAINT MONO (-3365 5910);
DISPLAY INVISIBLE (-3365 5910);
FORCEPROP 1 LASTPIN (-3375 5900) BN 5
J 0
(-3387 5908);
DISPLAY 0.489362 (-3387 5908);
PAINT GREEN (-3387 5908);
FORCEPROP 2 LAST CDS_LIB mstr_standard
J 0
(-3325 5900);
DISPLAY 0.723404 (-3325 5900);
PAINT MONO (-3325 5900);
DISPLAY INVISIBLE (-3325 5900);
FORCEPROP 1 LAST BODY_TYPE PLUMBING
J 0
(-3325 5950);
DISPLAY 0.872340 (-3325 5950);
PAINT GREEN (-3325 5950);
DISPLAY INVISIBLE (-3325 5950);
FORCEPROP 1 LAST HDL_TAP TRUE
J 0
(-3000 5775);
DISPLAY 0.872340 (-3000 5775);
DISPLAY INVISIBLE (-3000 5775);
FORCEPROP 1 LAST PATH I165
J 0
(-3327 5900);
DISPLAY 0.872340 (-3327 5900);
PAINT GREEN (-3327 5900);
DISPLAY INVISIBLE (-3327 5900);
FORCEADD TAP..1
(-3325 6000);
FORCEPROP 3 LASTPIN (-3375 6000) SIG_NAME M_F_CPU1_SA_DQ<3>
J 0
(-3365 6010);
DISPLAY 0.659574 (-3365 6010);
PAINT MONO (-3365 6010);
DISPLAY INVISIBLE (-3365 6010);
FORCEPROP 1 LASTPIN (-3375 6000) BN 3
J 0
(-3387 6008);
DISPLAY 0.489362 (-3387 6008);
PAINT GREEN (-3387 6008);
FORCEPROP 2 LAST CDS_LIB mstr_standard
J 0
(-3325 6000);
DISPLAY 0.723404 (-3325 6000);
PAINT MONO (-3325 6000);
DISPLAY INVISIBLE (-3325 6000);
FORCEPROP 1 LAST BODY_TYPE PLUMBING
J 0
(-3325 6050);
DISPLAY 0.872340 (-3325 6050);
PAINT GREEN (-3325 6050);
DISPLAY INVISIBLE (-3325 6050);
FORCEPROP 1 LAST HDL_TAP TRUE
J 0
(-3000 5875);
DISPLAY 0.872340 (-3000 5875);
DISPLAY INVISIBLE (-3000 5875);
FORCEPROP 1 LAST PATH I166
J 0
(-3327 6000);
DISPLAY 0.872340 (-3327 6000);
PAINT GREEN (-3327 6000);
DISPLAY INVISIBLE (-3327 6000);
FORCEADD TAP..1
(-3325 5950);
FORCEPROP 3 LASTPIN (-3375 5950) SIG_NAME M_F_CPU1_SA_DQ<4>
J 0
(-3365 5960);
DISPLAY 0.659574 (-3365 5960);
PAINT MONO (-3365 5960);
DISPLAY INVISIBLE (-3365 5960);
FORCEPROP 1 LASTPIN (-3375 5950) BN 4
J 0
(-3387 5958);
DISPLAY 0.489362 (-3387 5958);
PAINT GREEN (-3387 5958);
FORCEPROP 2 LAST CDS_LIB mstr_standard
J 0
(-3325 5950);
DISPLAY 0.723404 (-3325 5950);
PAINT MONO (-3325 5950);
DISPLAY INVISIBLE (-3325 5950);
FORCEPROP 1 LAST BODY_TYPE PLUMBING
J 0
(-3325 6000);
DISPLAY 0.872340 (-3325 6000);
PAINT GREEN (-3325 6000);
DISPLAY INVISIBLE (-3325 6000);
FORCEPROP 1 LAST HDL_TAP TRUE
J 0
(-3000 5825);
DISPLAY 0.872340 (-3000 5825);
DISPLAY INVISIBLE (-3000 5825);
FORCEPROP 1 LAST PATH I167
J 0
(-3327 5950);
DISPLAY 0.872340 (-3327 5950);
PAINT GREEN (-3327 5950);
DISPLAY INVISIBLE (-3327 5950);
FORCEADD TAP..1
(-3325 5850);
FORCEPROP 3 LASTPIN (-3375 5850) SIG_NAME M_F_CPU1_SA_DQ<6>
J 0
(-3365 5860);
DISPLAY 0.659574 (-3365 5860);
PAINT MONO (-3365 5860);
DISPLAY INVISIBLE (-3365 5860);
FORCEPROP 1 LASTPIN (-3375 5850) BN 6
J 0
(-3387 5858);
DISPLAY 0.489362 (-3387 5858);
PAINT GREEN (-3387 5858);
FORCEPROP 2 LAST CDS_LIB mstr_standard
J 0
(-3325 5850);
DISPLAY 0.723404 (-3325 5850);
PAINT MONO (-3325 5850);
DISPLAY INVISIBLE (-3325 5850);
FORCEPROP 1 LAST BODY_TYPE PLUMBING
J 0
(-3325 5900);
DISPLAY 0.872340 (-3325 5900);
PAINT GREEN (-3325 5900);
DISPLAY INVISIBLE (-3325 5900);
FORCEPROP 1 LAST HDL_TAP TRUE
J 0
(-3000 5725);
DISPLAY 0.872340 (-3000 5725);
DISPLAY INVISIBLE (-3000 5725);
FORCEPROP 1 LAST PATH I168
J 0
(-3327 5850);
DISPLAY 0.872340 (-3327 5850);
PAINT GREEN (-3327 5850);
DISPLAY INVISIBLE (-3327 5850);
FORCEADD TAP..1
(-3325 5800);
FORCEPROP 3 LASTPIN (-3375 5800) SIG_NAME M_F_CPU1_SA_DQ<7>
J 0
(-3365 5810);
DISPLAY 0.659574 (-3365 5810);
PAINT MONO (-3365 5810);
DISPLAY INVISIBLE (-3365 5810);
FORCEPROP 1 LASTPIN (-3375 5800) BN 7
J 0
(-3387 5808);
DISPLAY 0.489362 (-3387 5808);
PAINT GREEN (-3387 5808);
FORCEPROP 2 LAST CDS_LIB mstr_standard
J 0
(-3325 5800);
DISPLAY 0.723404 (-3325 5800);
PAINT MONO (-3325 5800);
DISPLAY INVISIBLE (-3325 5800);
FORCEPROP 1 LAST BODY_TYPE PLUMBING
J 0
(-3325 5850);
DISPLAY 0.872340 (-3325 5850);
PAINT GREEN (-3325 5850);
DISPLAY INVISIBLE (-3325 5850);
FORCEPROP 1 LAST HDL_TAP TRUE
J 0
(-3000 5675);
DISPLAY 0.872340 (-3000 5675);
DISPLAY INVISIBLE (-3000 5675);
FORCEPROP 1 LAST PATH I169
J 0
(-3327 5800);
DISPLAY 0.872340 (-3327 5800);
PAINT GREEN (-3327 5800);
DISPLAY INVISIBLE (-3327 5800);
FORCEADD TAP..1
(-3325 5700);
FORCEPROP 3 LASTPIN (-3375 5700) SIG_NAME M_F_CPU1_SA_DQ<8>
J 0
(-3365 5710);
DISPLAY 0.659574 (-3365 5710);
PAINT MONO (-3365 5710);
DISPLAY INVISIBLE (-3365 5710);
FORCEPROP 1 LASTPIN (-3375 5700) BN 8
J 0
(-3387 5708);
DISPLAY 0.489362 (-3387 5708);
PAINT GREEN (-3387 5708);
FORCEPROP 2 LAST CDS_LIB mstr_standard
J 0
(-3325 5700);
DISPLAY 0.723404 (-3325 5700);
PAINT MONO (-3325 5700);
DISPLAY INVISIBLE (-3325 5700);
FORCEPROP 1 LAST BODY_TYPE PLUMBING
J 0
(-3325 5750);
DISPLAY 0.872340 (-3325 5750);
PAINT GREEN (-3325 5750);
DISPLAY INVISIBLE (-3325 5750);
FORCEPROP 1 LAST HDL_TAP TRUE
J 0
(-3000 5575);
DISPLAY 0.872340 (-3000 5575);
DISPLAY INVISIBLE (-3000 5575);
FORCEPROP 1 LAST PATH I170
J 0
(-3327 5700);
DISPLAY 0.872340 (-3327 5700);
PAINT GREEN (-3327 5700);
DISPLAY INVISIBLE (-3327 5700);
FORCEADD TAP..1
(-3325 5650);
FORCEPROP 3 LASTPIN (-3375 5650) SIG_NAME M_F_CPU1_SA_DQ<9>
J 0
(-3365 5660);
DISPLAY 0.659574 (-3365 5660);
PAINT MONO (-3365 5660);
DISPLAY INVISIBLE (-3365 5660);
FORCEPROP 1 LASTPIN (-3375 5650) BN 9
J 0
(-3387 5658);
DISPLAY 0.489362 (-3387 5658);
PAINT GREEN (-3387 5658);
FORCEPROP 2 LAST CDS_LIB mstr_standard
J 0
(-3325 5650);
DISPLAY 0.723404 (-3325 5650);
PAINT MONO (-3325 5650);
DISPLAY INVISIBLE (-3325 5650);
FORCEPROP 1 LAST BODY_TYPE PLUMBING
J 0
(-3325 5700);
DISPLAY 0.872340 (-3325 5700);
PAINT GREEN (-3325 5700);
DISPLAY INVISIBLE (-3325 5700);
FORCEPROP 1 LAST HDL_TAP TRUE
J 0
(-3000 5525);
DISPLAY 0.872340 (-3000 5525);
DISPLAY INVISIBLE (-3000 5525);
FORCEPROP 1 LAST PATH I171
J 0
(-3327 5650);
DISPLAY 0.872340 (-3327 5650);
PAINT GREEN (-3327 5650);
DISPLAY INVISIBLE (-3327 5650);
FORCEADD TAP..1
(-3325 5550);
FORCEPROP 3 LASTPIN (-3375 5550) SIG_NAME M_F_CPU1_SA_DQ<11>
J 0
(-3365 5560);
DISPLAY 0.659574 (-3365 5560);
PAINT MONO (-3365 5560);
DISPLAY INVISIBLE (-3365 5560);
FORCEPROP 1 LASTPIN (-3375 5550) BN 11
J 0
(-3387 5558);
DISPLAY 0.489362 (-3387 5558);
PAINT GREEN (-3387 5558);
FORCEPROP 2 LAST CDS_LIB mstr_standard
J 0
(-3325 5550);
DISPLAY 0.723404 (-3325 5550);
PAINT MONO (-3325 5550);
DISPLAY INVISIBLE (-3325 5550);
FORCEPROP 1 LAST BODY_TYPE PLUMBING
J 0
(-3325 5600);
DISPLAY 0.872340 (-3325 5600);
PAINT GREEN (-3325 5600);
DISPLAY INVISIBLE (-3325 5600);
FORCEPROP 1 LAST HDL_TAP TRUE
J 0
(-3000 5425);
DISPLAY 0.872340 (-3000 5425);
DISPLAY INVISIBLE (-3000 5425);
FORCEPROP 1 LAST PATH I172
J 0
(-3327 5550);
DISPLAY 0.872340 (-3327 5550);
PAINT GREEN (-3327 5550);
DISPLAY INVISIBLE (-3327 5550);
FORCEADD TAP..1
(-3325 5600);
FORCEPROP 3 LASTPIN (-3375 5600) SIG_NAME M_F_CPU1_SA_DQ<10>
J 0
(-3365 5610);
DISPLAY 0.659574 (-3365 5610);
PAINT MONO (-3365 5610);
DISPLAY INVISIBLE (-3365 5610);
FORCEPROP 1 LASTPIN (-3375 5600) BN 10
J 0
(-3387 5608);
DISPLAY 0.489362 (-3387 5608);
PAINT GREEN (-3387 5608);
FORCEPROP 2 LAST CDS_LIB mstr_standard
J 0
(-3325 5600);
DISPLAY 0.723404 (-3325 5600);
PAINT MONO (-3325 5600);
DISPLAY INVISIBLE (-3325 5600);
FORCEPROP 1 LAST BODY_TYPE PLUMBING
J 0
(-3325 5650);
DISPLAY 0.872340 (-3325 5650);
PAINT GREEN (-3325 5650);
DISPLAY INVISIBLE (-3325 5650);
FORCEPROP 1 LAST HDL_TAP TRUE
J 0
(-3000 5475);
DISPLAY 0.872340 (-3000 5475);
DISPLAY INVISIBLE (-3000 5475);
FORCEPROP 1 LAST PATH I173
J 0
(-3327 5600);
DISPLAY 0.872340 (-3327 5600);
PAINT GREEN (-3327 5600);
DISPLAY INVISIBLE (-3327 5600);
FORCEADD TAP..1
(-3325 5450);
FORCEPROP 3 LASTPIN (-3375 5450) SIG_NAME M_F_CPU1_SA_DQ<13>
J 0
(-3365 5460);
DISPLAY 0.659574 (-3365 5460);
PAINT MONO (-3365 5460);
DISPLAY INVISIBLE (-3365 5460);
FORCEPROP 1 LASTPIN (-3375 5450) BN 13
J 0
(-3387 5458);
DISPLAY 0.489362 (-3387 5458);
PAINT GREEN (-3387 5458);
FORCEPROP 2 LAST CDS_LIB mstr_standard
J 0
(-3325 5450);
DISPLAY 0.723404 (-3325 5450);
PAINT MONO (-3325 5450);
DISPLAY INVISIBLE (-3325 5450);
FORCEPROP 1 LAST BODY_TYPE PLUMBING
J 0
(-3325 5500);
DISPLAY 0.872340 (-3325 5500);
PAINT GREEN (-3325 5500);
DISPLAY INVISIBLE (-3325 5500);
FORCEPROP 1 LAST HDL_TAP TRUE
J 0
(-3000 5325);
DISPLAY 0.872340 (-3000 5325);
DISPLAY INVISIBLE (-3000 5325);
FORCEPROP 1 LAST PATH I174
J 0
(-3327 5450);
DISPLAY 0.872340 (-3327 5450);
PAINT GREEN (-3327 5450);
DISPLAY INVISIBLE (-3327 5450);
FORCEADD TAP..1
(-3325 5500);
FORCEPROP 3 LASTPIN (-3375 5500) SIG_NAME M_F_CPU1_SA_DQ<12>
J 0
(-3365 5510);
DISPLAY 0.659574 (-3365 5510);
PAINT MONO (-3365 5510);
DISPLAY INVISIBLE (-3365 5510);
FORCEPROP 1 LASTPIN (-3375 5500) BN 12
J 0
(-3387 5508);
DISPLAY 0.489362 (-3387 5508);
PAINT GREEN (-3387 5508);
FORCEPROP 2 LAST CDS_LIB mstr_standard
J 0
(-3325 5500);
DISPLAY 0.723404 (-3325 5500);
PAINT MONO (-3325 5500);
DISPLAY INVISIBLE (-3325 5500);
FORCEPROP 1 LAST BODY_TYPE PLUMBING
J 0
(-3325 5550);
DISPLAY 0.872340 (-3325 5550);
PAINT GREEN (-3325 5550);
DISPLAY INVISIBLE (-3325 5550);
FORCEPROP 1 LAST HDL_TAP TRUE
J 0
(-3000 5375);
DISPLAY 0.872340 (-3000 5375);
DISPLAY INVISIBLE (-3000 5375);
FORCEPROP 1 LAST PATH I175
J 0
(-3327 5500);
DISPLAY 0.872340 (-3327 5500);
PAINT GREEN (-3327 5500);
DISPLAY INVISIBLE (-3327 5500);
FORCEADD TAP..1
(-3325 5400);
FORCEPROP 3 LASTPIN (-3375 5400) SIG_NAME M_F_CPU1_SA_DQ<14>
J 0
(-3365 5410);
DISPLAY 0.659574 (-3365 5410);
PAINT MONO (-3365 5410);
DISPLAY INVISIBLE (-3365 5410);
FORCEPROP 1 LASTPIN (-3375 5400) BN 14
J 0
(-3387 5408);
DISPLAY 0.489362 (-3387 5408);
PAINT GREEN (-3387 5408);
FORCEPROP 2 LAST CDS_LIB mstr_standard
J 0
(-3325 5400);
DISPLAY 0.723404 (-3325 5400);
PAINT MONO (-3325 5400);
DISPLAY INVISIBLE (-3325 5400);
FORCEPROP 1 LAST BODY_TYPE PLUMBING
J 0
(-3325 5450);
DISPLAY 0.872340 (-3325 5450);
PAINT GREEN (-3325 5450);
DISPLAY INVISIBLE (-3325 5450);
FORCEPROP 1 LAST HDL_TAP TRUE
J 0
(-3000 5275);
DISPLAY 0.872340 (-3000 5275);
DISPLAY INVISIBLE (-3000 5275);
FORCEPROP 1 LAST PATH I176
J 0
(-3327 5400);
DISPLAY 0.872340 (-3327 5400);
PAINT GREEN (-3327 5400);
DISPLAY INVISIBLE (-3327 5400);
FORCEADD TAP..1
(-3325 5350);
FORCEPROP 3 LASTPIN (-3375 5350) SIG_NAME M_F_CPU1_SA_DQ<15>
J 0
(-3365 5360);
DISPLAY 0.659574 (-3365 5360);
PAINT MONO (-3365 5360);
DISPLAY INVISIBLE (-3365 5360);
FORCEPROP 1 LASTPIN (-3375 5350) BN 15
J 0
(-3387 5358);
DISPLAY 0.489362 (-3387 5358);
PAINT GREEN (-3387 5358);
FORCEPROP 2 LAST CDS_LIB mstr_standard
J 0
(-3325 5350);
DISPLAY 0.723404 (-3325 5350);
PAINT MONO (-3325 5350);
DISPLAY INVISIBLE (-3325 5350);
FORCEPROP 1 LAST BODY_TYPE PLUMBING
J 0
(-3325 5400);
DISPLAY 0.872340 (-3325 5400);
PAINT GREEN (-3325 5400);
DISPLAY INVISIBLE (-3325 5400);
FORCEPROP 1 LAST HDL_TAP TRUE
J 0
(-3000 5225);
DISPLAY 0.872340 (-3000 5225);
DISPLAY INVISIBLE (-3000 5225);
FORCEPROP 1 LAST PATH I177
J 0
(-3327 5350);
DISPLAY 0.872340 (-3327 5350);
PAINT GREEN (-3327 5350);
DISPLAY INVISIBLE (-3327 5350);
FORCEADD TAP..1
(-3325 5250);
FORCEPROP 3 LASTPIN (-3375 5250) SIG_NAME M_F_CPU1_SA_DQ<16>
J 0
(-3365 5260);
DISPLAY 0.659574 (-3365 5260);
PAINT MONO (-3365 5260);
DISPLAY INVISIBLE (-3365 5260);
FORCEPROP 1 LASTPIN (-3375 5250) BN 16
J 0
(-3387 5258);
DISPLAY 0.489362 (-3387 5258);
PAINT GREEN (-3387 5258);
FORCEPROP 2 LAST CDS_LIB mstr_standard
J 0
(-3325 5250);
DISPLAY 0.723404 (-3325 5250);
PAINT MONO (-3325 5250);
DISPLAY INVISIBLE (-3325 5250);
FORCEPROP 1 LAST BODY_TYPE PLUMBING
J 0
(-3325 5300);
DISPLAY 0.872340 (-3325 5300);
PAINT GREEN (-3325 5300);
DISPLAY INVISIBLE (-3325 5300);
FORCEPROP 1 LAST HDL_TAP TRUE
J 0
(-3000 5125);
DISPLAY 0.872340 (-3000 5125);
DISPLAY INVISIBLE (-3000 5125);
FORCEPROP 1 LAST PATH I178
J 0
(-3327 5250);
DISPLAY 0.872340 (-3327 5250);
PAINT GREEN (-3327 5250);
DISPLAY INVISIBLE (-3327 5250);
FORCEADD TAP..1
(-3325 5200);
FORCEPROP 3 LASTPIN (-3375 5200) SIG_NAME M_F_CPU1_SA_DQ<17>
J 0
(-3365 5210);
DISPLAY 0.659574 (-3365 5210);
PAINT MONO (-3365 5210);
DISPLAY INVISIBLE (-3365 5210);
FORCEPROP 1 LASTPIN (-3375 5200) BN 17
J 0
(-3387 5208);
DISPLAY 0.489362 (-3387 5208);
PAINT GREEN (-3387 5208);
FORCEPROP 2 LAST CDS_LIB mstr_standard
J 0
(-3325 5200);
DISPLAY 0.723404 (-3325 5200);
PAINT MONO (-3325 5200);
DISPLAY INVISIBLE (-3325 5200);
FORCEPROP 1 LAST BODY_TYPE PLUMBING
J 0
(-3325 5250);
DISPLAY 0.872340 (-3325 5250);
PAINT GREEN (-3325 5250);
DISPLAY INVISIBLE (-3325 5250);
FORCEPROP 1 LAST HDL_TAP TRUE
J 0
(-3000 5075);
DISPLAY 0.872340 (-3000 5075);
DISPLAY INVISIBLE (-3000 5075);
FORCEPROP 1 LAST PATH I179
J 0
(-3327 5200);
DISPLAY 0.872340 (-3327 5200);
PAINT GREEN (-3327 5200);
DISPLAY INVISIBLE (-3327 5200);
FORCEADD TAP..1
(-3325 5150);
FORCEPROP 3 LASTPIN (-3375 5150) SIG_NAME M_F_CPU1_SA_DQ<18>
J 0
(-3365 5160);
DISPLAY 0.659574 (-3365 5160);
PAINT MONO (-3365 5160);
DISPLAY INVISIBLE (-3365 5160);
FORCEPROP 1 LASTPIN (-3375 5150) BN 18
J 0
(-3387 5158);
DISPLAY 0.489362 (-3387 5158);
PAINT GREEN (-3387 5158);
FORCEPROP 2 LAST CDS_LIB mstr_standard
J 0
(-3325 5150);
DISPLAY 0.723404 (-3325 5150);
PAINT MONO (-3325 5150);
DISPLAY INVISIBLE (-3325 5150);
FORCEPROP 1 LAST BODY_TYPE PLUMBING
J 0
(-3325 5200);
DISPLAY 0.872340 (-3325 5200);
PAINT GREEN (-3325 5200);
DISPLAY INVISIBLE (-3325 5200);
FORCEPROP 1 LAST HDL_TAP TRUE
J 0
(-3000 5025);
DISPLAY 0.872340 (-3000 5025);
DISPLAY INVISIBLE (-3000 5025);
FORCEPROP 1 LAST PATH I180
J 0
(-3327 5150);
DISPLAY 0.872340 (-3327 5150);
PAINT GREEN (-3327 5150);
DISPLAY INVISIBLE (-3327 5150);
FORCEADD TAP..1
(-3325 5100);
FORCEPROP 3 LASTPIN (-3375 5100) SIG_NAME M_F_CPU1_SA_DQ<19>
J 0
(-3365 5110);
DISPLAY 0.659574 (-3365 5110);
PAINT MONO (-3365 5110);
DISPLAY INVISIBLE (-3365 5110);
FORCEPROP 1 LASTPIN (-3375 5100) BN 19
J 0
(-3387 5108);
DISPLAY 0.489362 (-3387 5108);
PAINT GREEN (-3387 5108);
FORCEPROP 2 LAST CDS_LIB mstr_standard
J 0
(-3325 5100);
DISPLAY 0.723404 (-3325 5100);
PAINT MONO (-3325 5100);
DISPLAY INVISIBLE (-3325 5100);
FORCEPROP 1 LAST BODY_TYPE PLUMBING
J 0
(-3325 5150);
DISPLAY 0.872340 (-3325 5150);
PAINT GREEN (-3325 5150);
DISPLAY INVISIBLE (-3325 5150);
FORCEPROP 1 LAST HDL_TAP TRUE
J 0
(-3000 4975);
DISPLAY 0.872340 (-3000 4975);
DISPLAY INVISIBLE (-3000 4975);
FORCEPROP 1 LAST PATH I181
J 0
(-3327 5100);
DISPLAY 0.872340 (-3327 5100);
PAINT GREEN (-3327 5100);
DISPLAY INVISIBLE (-3327 5100);
FORCEADD TAP..1
(-3325 5050);
FORCEPROP 3 LASTPIN (-3375 5050) SIG_NAME M_F_CPU1_SA_DQ<20>
J 0
(-3365 5060);
DISPLAY 0.659574 (-3365 5060);
PAINT MONO (-3365 5060);
DISPLAY INVISIBLE (-3365 5060);
FORCEPROP 1 LASTPIN (-3375 5050) BN 20
J 0
(-3387 5058);
DISPLAY 0.489362 (-3387 5058);
PAINT GREEN (-3387 5058);
FORCEPROP 2 LAST CDS_LIB mstr_standard
J 0
(-3325 5050);
DISPLAY 0.723404 (-3325 5050);
PAINT MONO (-3325 5050);
DISPLAY INVISIBLE (-3325 5050);
FORCEPROP 1 LAST BODY_TYPE PLUMBING
J 0
(-3325 5100);
DISPLAY 0.872340 (-3325 5100);
PAINT GREEN (-3325 5100);
DISPLAY INVISIBLE (-3325 5100);
FORCEPROP 1 LAST HDL_TAP TRUE
J 0
(-3000 4925);
DISPLAY 0.872340 (-3000 4925);
DISPLAY INVISIBLE (-3000 4925);
FORCEPROP 1 LAST PATH I182
J 0
(-3327 5050);
DISPLAY 0.872340 (-3327 5050);
PAINT GREEN (-3327 5050);
DISPLAY INVISIBLE (-3327 5050);
FORCEADD TAP..1
(-3325 5000);
FORCEPROP 3 LASTPIN (-3375 5000) SIG_NAME M_F_CPU1_SA_DQ<21>
J 0
(-3365 5010);
DISPLAY 0.659574 (-3365 5010);
PAINT MONO (-3365 5010);
DISPLAY INVISIBLE (-3365 5010);
FORCEPROP 1 LASTPIN (-3375 5000) BN 21
J 0
(-3387 5008);
DISPLAY 0.489362 (-3387 5008);
PAINT GREEN (-3387 5008);
FORCEPROP 2 LAST CDS_LIB mstr_standard
J 0
(-3325 5000);
DISPLAY 0.723404 (-3325 5000);
PAINT MONO (-3325 5000);
DISPLAY INVISIBLE (-3325 5000);
FORCEPROP 1 LAST BODY_TYPE PLUMBING
J 0
(-3325 5050);
DISPLAY 0.872340 (-3325 5050);
PAINT GREEN (-3325 5050);
DISPLAY INVISIBLE (-3325 5050);
FORCEPROP 1 LAST HDL_TAP TRUE
J 0
(-3000 4875);
DISPLAY 0.872340 (-3000 4875);
DISPLAY INVISIBLE (-3000 4875);
FORCEPROP 1 LAST PATH I183
J 0
(-3327 5000);
DISPLAY 0.872340 (-3327 5000);
PAINT GREEN (-3327 5000);
DISPLAY INVISIBLE (-3327 5000);
FORCEADD TAP..1
(-3325 4900);
FORCEPROP 3 LASTPIN (-3375 4900) SIG_NAME M_F_CPU1_SA_DQ<23>
J 0
(-3365 4910);
DISPLAY 0.659574 (-3365 4910);
PAINT MONO (-3365 4910);
DISPLAY INVISIBLE (-3365 4910);
FORCEPROP 1 LASTPIN (-3375 4900) BN 23
J 0
(-3387 4908);
DISPLAY 0.489362 (-3387 4908);
PAINT GREEN (-3387 4908);
FORCEPROP 2 LAST CDS_LIB mstr_standard
J 0
(-3325 4900);
DISPLAY 0.723404 (-3325 4900);
PAINT MONO (-3325 4900);
DISPLAY INVISIBLE (-3325 4900);
FORCEPROP 1 LAST BODY_TYPE PLUMBING
J 0
(-3325 4950);
DISPLAY 0.872340 (-3325 4950);
PAINT GREEN (-3325 4950);
DISPLAY INVISIBLE (-3325 4950);
FORCEPROP 1 LAST HDL_TAP TRUE
J 0
(-3000 4775);
DISPLAY 0.872340 (-3000 4775);
DISPLAY INVISIBLE (-3000 4775);
FORCEPROP 1 LAST PATH I184
J 0
(-3327 4900);
DISPLAY 0.872340 (-3327 4900);
PAINT GREEN (-3327 4900);
DISPLAY INVISIBLE (-3327 4900);
FORCEADD TAP..1
(-3325 4950);
FORCEPROP 3 LASTPIN (-3375 4950) SIG_NAME M_F_CPU1_SA_DQ<22>
J 0
(-3365 4960);
DISPLAY 0.659574 (-3365 4960);
PAINT MONO (-3365 4960);
DISPLAY INVISIBLE (-3365 4960);
FORCEPROP 1 LASTPIN (-3375 4950) BN 22
J 0
(-3387 4958);
DISPLAY 0.489362 (-3387 4958);
PAINT GREEN (-3387 4958);
FORCEPROP 2 LAST CDS_LIB mstr_standard
J 0
(-3325 4950);
DISPLAY 0.723404 (-3325 4950);
PAINT MONO (-3325 4950);
DISPLAY INVISIBLE (-3325 4950);
FORCEPROP 1 LAST BODY_TYPE PLUMBING
J 0
(-3325 5000);
DISPLAY 0.872340 (-3325 5000);
PAINT GREEN (-3325 5000);
DISPLAY INVISIBLE (-3325 5000);
FORCEPROP 1 LAST HDL_TAP TRUE
J 0
(-3000 4825);
DISPLAY 0.872340 (-3000 4825);
DISPLAY INVISIBLE (-3000 4825);
FORCEPROP 1 LAST PATH I185
J 0
(-3327 4950);
DISPLAY 0.872340 (-3327 4950);
PAINT GREEN (-3327 4950);
DISPLAY INVISIBLE (-3327 4950);
FORCEADD TAP..1
(-3325 4750);
FORCEPROP 3 LASTPIN (-3375 4750) SIG_NAME M_F_CPU1_SA_DQ<25>
J 0
(-3365 4760);
DISPLAY 0.659574 (-3365 4760);
PAINT MONO (-3365 4760);
DISPLAY INVISIBLE (-3365 4760);
FORCEPROP 1 LASTPIN (-3375 4750) BN 25
J 0
(-3387 4758);
DISPLAY 0.489362 (-3387 4758);
PAINT GREEN (-3387 4758);
FORCEPROP 2 LAST CDS_LIB mstr_standard
J 0
(-3325 4750);
DISPLAY 0.723404 (-3325 4750);
PAINT MONO (-3325 4750);
DISPLAY INVISIBLE (-3325 4750);
FORCEPROP 1 LAST BODY_TYPE PLUMBING
J 0
(-3325 4800);
DISPLAY 0.872340 (-3325 4800);
PAINT GREEN (-3325 4800);
DISPLAY INVISIBLE (-3325 4800);
FORCEPROP 1 LAST HDL_TAP TRUE
J 0
(-3000 4625);
DISPLAY 0.872340 (-3000 4625);
DISPLAY INVISIBLE (-3000 4625);
FORCEPROP 1 LAST PATH I186
J 0
(-3327 4750);
DISPLAY 0.872340 (-3327 4750);
PAINT GREEN (-3327 4750);
DISPLAY INVISIBLE (-3327 4750);
FORCEADD TAP..1
(-3325 4800);
FORCEPROP 3 LASTPIN (-3375 4800) SIG_NAME M_F_CPU1_SA_DQ<24>
J 0
(-3365 4810);
DISPLAY 0.659574 (-3365 4810);
PAINT MONO (-3365 4810);
DISPLAY INVISIBLE (-3365 4810);
FORCEPROP 1 LASTPIN (-3375 4800) BN 24
J 0
(-3387 4808);
DISPLAY 0.489362 (-3387 4808);
PAINT GREEN (-3387 4808);
FORCEPROP 2 LAST CDS_LIB mstr_standard
J 0
(-3325 4800);
DISPLAY 0.723404 (-3325 4800);
PAINT MONO (-3325 4800);
DISPLAY INVISIBLE (-3325 4800);
FORCEPROP 1 LAST BODY_TYPE PLUMBING
J 0
(-3325 4850);
DISPLAY 0.872340 (-3325 4850);
PAINT GREEN (-3325 4850);
DISPLAY INVISIBLE (-3325 4850);
FORCEPROP 1 LAST HDL_TAP TRUE
J 0
(-3000 4675);
DISPLAY 0.872340 (-3000 4675);
DISPLAY INVISIBLE (-3000 4675);
FORCEPROP 1 LAST PATH I187
J 0
(-3327 4800);
DISPLAY 0.872340 (-3327 4800);
PAINT GREEN (-3327 4800);
DISPLAY INVISIBLE (-3327 4800);
FORCEADD TAP..1
(-3325 4700);
FORCEPROP 3 LASTPIN (-3375 4700) SIG_NAME M_F_CPU1_SA_DQ<26>
J 0
(-3365 4710);
DISPLAY 0.659574 (-3365 4710);
PAINT MONO (-3365 4710);
DISPLAY INVISIBLE (-3365 4710);
FORCEPROP 1 LASTPIN (-3375 4700) BN 26
J 0
(-3387 4708);
DISPLAY 0.489362 (-3387 4708);
PAINT GREEN (-3387 4708);
FORCEPROP 2 LAST CDS_LIB mstr_standard
J 0
(-3325 4700);
DISPLAY 0.723404 (-3325 4700);
PAINT MONO (-3325 4700);
DISPLAY INVISIBLE (-3325 4700);
FORCEPROP 1 LAST BODY_TYPE PLUMBING
J 0
(-3325 4750);
DISPLAY 0.872340 (-3325 4750);
PAINT GREEN (-3325 4750);
DISPLAY INVISIBLE (-3325 4750);
FORCEPROP 1 LAST HDL_TAP TRUE
J 0
(-3000 4575);
DISPLAY 0.872340 (-3000 4575);
DISPLAY INVISIBLE (-3000 4575);
FORCEPROP 1 LAST PATH I188
J 0
(-3327 4700);
DISPLAY 0.872340 (-3327 4700);
PAINT GREEN (-3327 4700);
DISPLAY INVISIBLE (-3327 4700);
FORCEADD TAP..1
(-3325 4650);
FORCEPROP 3 LASTPIN (-3375 4650) SIG_NAME M_F_CPU1_SA_DQ<27>
J 0
(-3365 4660);
DISPLAY 0.659574 (-3365 4660);
PAINT MONO (-3365 4660);
DISPLAY INVISIBLE (-3365 4660);
FORCEPROP 1 LASTPIN (-3375 4650) BN 27
J 0
(-3387 4658);
DISPLAY 0.489362 (-3387 4658);
PAINT GREEN (-3387 4658);
FORCEPROP 2 LAST CDS_LIB mstr_standard
J 0
(-3325 4650);
DISPLAY 0.723404 (-3325 4650);
PAINT MONO (-3325 4650);
DISPLAY INVISIBLE (-3325 4650);
FORCEPROP 1 LAST BODY_TYPE PLUMBING
J 0
(-3325 4700);
DISPLAY 0.872340 (-3325 4700);
PAINT GREEN (-3325 4700);
DISPLAY INVISIBLE (-3325 4700);
FORCEPROP 1 LAST HDL_TAP TRUE
J 0
(-3000 4525);
DISPLAY 0.872340 (-3000 4525);
DISPLAY INVISIBLE (-3000 4525);
FORCEPROP 1 LAST PATH I189
J 0
(-3327 4650);
DISPLAY 0.872340 (-3327 4650);
PAINT GREEN (-3327 4650);
DISPLAY INVISIBLE (-3327 4650);
FORCEADD TAP..1
(-3325 4600);
FORCEPROP 3 LASTPIN (-3375 4600) SIG_NAME M_F_CPU1_SA_DQ<28>
J 0
(-3365 4610);
DISPLAY 0.659574 (-3365 4610);
PAINT MONO (-3365 4610);
DISPLAY INVISIBLE (-3365 4610);
FORCEPROP 1 LASTPIN (-3375 4600) BN 28
J 0
(-3387 4608);
DISPLAY 0.489362 (-3387 4608);
PAINT GREEN (-3387 4608);
FORCEPROP 2 LAST CDS_LIB mstr_standard
J 0
(-3325 4600);
DISPLAY 0.723404 (-3325 4600);
PAINT MONO (-3325 4600);
DISPLAY INVISIBLE (-3325 4600);
FORCEPROP 1 LAST BODY_TYPE PLUMBING
J 0
(-3325 4650);
DISPLAY 0.872340 (-3325 4650);
PAINT GREEN (-3325 4650);
DISPLAY INVISIBLE (-3325 4650);
FORCEPROP 1 LAST HDL_TAP TRUE
J 0
(-3000 4475);
DISPLAY 0.872340 (-3000 4475);
DISPLAY INVISIBLE (-3000 4475);
FORCEPROP 1 LAST PATH I190
J 0
(-3327 4600);
DISPLAY 0.872340 (-3327 4600);
PAINT GREEN (-3327 4600);
DISPLAY INVISIBLE (-3327 4600);
FORCEADD TAP..1
(-3325 4500);
FORCEPROP 3 LASTPIN (-3375 4500) SIG_NAME M_F_CPU1_SA_DQ<30>
J 0
(-3365 4510);
DISPLAY 0.659574 (-3365 4510);
PAINT MONO (-3365 4510);
DISPLAY INVISIBLE (-3365 4510);
FORCEPROP 1 LASTPIN (-3375 4500) BN 30
J 0
(-3387 4508);
DISPLAY 0.489362 (-3387 4508);
PAINT GREEN (-3387 4508);
FORCEPROP 2 LAST CDS_LIB mstr_standard
J 0
(-3325 4500);
DISPLAY 0.723404 (-3325 4500);
PAINT MONO (-3325 4500);
DISPLAY INVISIBLE (-3325 4500);
FORCEPROP 1 LAST BODY_TYPE PLUMBING
J 0
(-3325 4550);
DISPLAY 0.872340 (-3325 4550);
PAINT GREEN (-3325 4550);
DISPLAY INVISIBLE (-3325 4550);
FORCEPROP 1 LAST HDL_TAP TRUE
J 0
(-3000 4375);
DISPLAY 0.872340 (-3000 4375);
DISPLAY INVISIBLE (-3000 4375);
FORCEPROP 1 LAST PATH I191
J 0
(-3327 4500);
DISPLAY 0.872340 (-3327 4500);
PAINT GREEN (-3327 4500);
DISPLAY INVISIBLE (-3327 4500);
FORCEADD TAP..1
(-3325 4550);
FORCEPROP 3 LASTPIN (-3375 4550) SIG_NAME M_F_CPU1_SA_DQ<29>
J 0
(-3365 4560);
DISPLAY 0.659574 (-3365 4560);
PAINT MONO (-3365 4560);
DISPLAY INVISIBLE (-3365 4560);
FORCEPROP 1 LASTPIN (-3375 4550) BN 29
J 0
(-3387 4558);
DISPLAY 0.489362 (-3387 4558);
PAINT GREEN (-3387 4558);
FORCEPROP 2 LAST CDS_LIB mstr_standard
J 0
(-3325 4550);
DISPLAY 0.723404 (-3325 4550);
PAINT MONO (-3325 4550);
DISPLAY INVISIBLE (-3325 4550);
FORCEPROP 1 LAST BODY_TYPE PLUMBING
J 0
(-3325 4600);
DISPLAY 0.872340 (-3325 4600);
PAINT GREEN (-3325 4600);
DISPLAY INVISIBLE (-3325 4600);
FORCEPROP 1 LAST HDL_TAP TRUE
J 0
(-3000 4425);
DISPLAY 0.872340 (-3000 4425);
DISPLAY INVISIBLE (-3000 4425);
FORCEPROP 1 LAST PATH I192
J 0
(-3327 4550);
DISPLAY 0.872340 (-3327 4550);
PAINT GREEN (-3327 4550);
DISPLAY INVISIBLE (-3327 4550);
FORCEADD TAP..1
(-3325 4450);
FORCEPROP 3 LASTPIN (-3375 4450) SIG_NAME M_F_CPU1_SA_DQ<31>
J 0
(-3365 4460);
DISPLAY 0.659574 (-3365 4460);
PAINT MONO (-3365 4460);
DISPLAY INVISIBLE (-3365 4460);
FORCEPROP 1 LASTPIN (-3375 4450) BN 31
J 0
(-3387 4458);
DISPLAY 0.489362 (-3387 4458);
PAINT GREEN (-3387 4458);
FORCEPROP 2 LAST CDS_LIB mstr_standard
J 0
(-3325 4450);
DISPLAY 0.723404 (-3325 4450);
PAINT MONO (-3325 4450);
DISPLAY INVISIBLE (-3325 4450);
FORCEPROP 1 LAST BODY_TYPE PLUMBING
J 0
(-3325 4500);
DISPLAY 0.872340 (-3325 4500);
PAINT GREEN (-3325 4500);
DISPLAY INVISIBLE (-3325 4500);
FORCEPROP 1 LAST HDL_TAP TRUE
J 0
(-3000 4325);
DISPLAY 0.872340 (-3000 4325);
DISPLAY INVISIBLE (-3000 4325);
FORCEPROP 1 LAST PATH I193
J 0
(-3327 4450);
DISPLAY 0.872340 (-3327 4450);
PAINT GREEN (-3327 4450);
DISPLAY INVISIBLE (-3327 4450);
FORCEADD TAP..1
(-3325 4350);
FORCEPROP 3 LASTPIN (-3375 4350) SIG_NAME M_F_CPU1_SB_DQ<0>
J 0
(-3365 4360);
DISPLAY 0.659574 (-3365 4360);
PAINT MONO (-3365 4360);
DISPLAY INVISIBLE (-3365 4360);
FORCEPROP 1 LASTPIN (-3375 4350) BN 0
J 0
(-3387 4358);
DISPLAY 0.489362 (-3387 4358);
PAINT GREEN (-3387 4358);
FORCEPROP 2 LAST CDS_LIB mstr_standard
J 0
(-3325 4350);
DISPLAY 0.723404 (-3325 4350);
PAINT MONO (-3325 4350);
DISPLAY INVISIBLE (-3325 4350);
FORCEPROP 1 LAST BODY_TYPE PLUMBING
J 0
(-3325 4400);
DISPLAY 0.872340 (-3325 4400);
PAINT GREEN (-3325 4400);
DISPLAY INVISIBLE (-3325 4400);
FORCEPROP 1 LAST HDL_TAP TRUE
J 0
(-3000 4225);
DISPLAY 0.872340 (-3000 4225);
DISPLAY INVISIBLE (-3000 4225);
FORCEPROP 1 LAST PATH I194
J 0
(-3327 4350);
DISPLAY 0.872340 (-3327 4350);
PAINT GREEN (-3327 4350);
DISPLAY INVISIBLE (-3327 4350);
FORCEADD TAP..1
(-3325 4300);
FORCEPROP 3 LASTPIN (-3375 4300) SIG_NAME M_F_CPU1_SB_DQ<1>
J 0
(-3365 4310);
DISPLAY 0.659574 (-3365 4310);
PAINT MONO (-3365 4310);
DISPLAY INVISIBLE (-3365 4310);
FORCEPROP 1 LASTPIN (-3375 4300) BN 1
J 0
(-3387 4308);
DISPLAY 0.489362 (-3387 4308);
PAINT GREEN (-3387 4308);
FORCEPROP 2 LAST CDS_LIB mstr_standard
J 0
(-3325 4300);
DISPLAY 0.723404 (-3325 4300);
PAINT MONO (-3325 4300);
DISPLAY INVISIBLE (-3325 4300);
FORCEPROP 1 LAST BODY_TYPE PLUMBING
J 0
(-3325 4350);
DISPLAY 0.872340 (-3325 4350);
PAINT GREEN (-3325 4350);
DISPLAY INVISIBLE (-3325 4350);
FORCEPROP 1 LAST HDL_TAP TRUE
J 0
(-3000 4175);
DISPLAY 0.872340 (-3000 4175);
DISPLAY INVISIBLE (-3000 4175);
FORCEPROP 1 LAST PATH I195
J 0
(-3327 4300);
DISPLAY 0.872340 (-3327 4300);
PAINT GREEN (-3327 4300);
DISPLAY INVISIBLE (-3327 4300);
FORCEADD TAP..1
(-3325 4250);
FORCEPROP 3 LASTPIN (-3375 4250) SIG_NAME M_F_CPU1_SB_DQ<2>
J 0
(-3365 4260);
DISPLAY 0.659574 (-3365 4260);
PAINT MONO (-3365 4260);
DISPLAY INVISIBLE (-3365 4260);
FORCEPROP 1 LASTPIN (-3375 4250) BN 2
J 0
(-3387 4258);
DISPLAY 0.489362 (-3387 4258);
PAINT GREEN (-3387 4258);
FORCEPROP 2 LAST CDS_LIB mstr_standard
J 0
(-3325 4250);
DISPLAY 0.723404 (-3325 4250);
PAINT MONO (-3325 4250);
DISPLAY INVISIBLE (-3325 4250);
FORCEPROP 1 LAST BODY_TYPE PLUMBING
J 0
(-3325 4300);
DISPLAY 0.872340 (-3325 4300);
PAINT GREEN (-3325 4300);
DISPLAY INVISIBLE (-3325 4300);
FORCEPROP 1 LAST HDL_TAP TRUE
J 0
(-3000 4125);
DISPLAY 0.872340 (-3000 4125);
DISPLAY INVISIBLE (-3000 4125);
FORCEPROP 1 LAST PATH I196
J 0
(-3327 4250);
DISPLAY 0.872340 (-3327 4250);
PAINT GREEN (-3327 4250);
DISPLAY INVISIBLE (-3327 4250);
FORCEADD TAP..1
(-3325 4150);
FORCEPROP 3 LASTPIN (-3375 4150) SIG_NAME M_F_CPU1_SB_DQ<4>
J 0
(-3365 4160);
DISPLAY 0.659574 (-3365 4160);
PAINT MONO (-3365 4160);
DISPLAY INVISIBLE (-3365 4160);
FORCEPROP 1 LASTPIN (-3375 4150) BN 4
J 0
(-3387 4158);
DISPLAY 0.489362 (-3387 4158);
PAINT GREEN (-3387 4158);
FORCEPROP 2 LAST CDS_LIB mstr_standard
J 0
(-3325 4150);
DISPLAY 0.723404 (-3325 4150);
PAINT MONO (-3325 4150);
DISPLAY INVISIBLE (-3325 4150);
FORCEPROP 1 LAST BODY_TYPE PLUMBING
J 0
(-3325 4200);
DISPLAY 0.872340 (-3325 4200);
PAINT GREEN (-3325 4200);
DISPLAY INVISIBLE (-3325 4200);
FORCEPROP 1 LAST HDL_TAP TRUE
J 0
(-3000 4025);
DISPLAY 0.872340 (-3000 4025);
DISPLAY INVISIBLE (-3000 4025);
FORCEPROP 1 LAST PATH I197
J 0
(-3327 4150);
DISPLAY 0.872340 (-3327 4150);
PAINT GREEN (-3327 4150);
DISPLAY INVISIBLE (-3327 4150);
FORCEADD TAP..1
(-3325 4200);
FORCEPROP 3 LASTPIN (-3375 4200) SIG_NAME M_F_CPU1_SB_DQ<3>
J 0
(-3365 4210);
DISPLAY 0.659574 (-3365 4210);
PAINT MONO (-3365 4210);
DISPLAY INVISIBLE (-3365 4210);
FORCEPROP 1 LASTPIN (-3375 4200) BN 3
J 0
(-3387 4208);
DISPLAY 0.489362 (-3387 4208);
PAINT GREEN (-3387 4208);
FORCEPROP 2 LAST CDS_LIB mstr_standard
J 0
(-3325 4200);
DISPLAY 0.723404 (-3325 4200);
PAINT MONO (-3325 4200);
DISPLAY INVISIBLE (-3325 4200);
FORCEPROP 1 LAST BODY_TYPE PLUMBING
J 0
(-3325 4250);
DISPLAY 0.872340 (-3325 4250);
PAINT GREEN (-3325 4250);
DISPLAY INVISIBLE (-3325 4250);
FORCEPROP 1 LAST HDL_TAP TRUE
J 0
(-3000 4075);
DISPLAY 0.872340 (-3000 4075);
DISPLAY INVISIBLE (-3000 4075);
FORCEPROP 1 LAST PATH I198
J 0
(-3327 4200);
DISPLAY 0.872340 (-3327 4200);
PAINT GREEN (-3327 4200);
DISPLAY INVISIBLE (-3327 4200);
FORCEADD TAP..1
(-3325 4100);
FORCEPROP 3 LASTPIN (-3375 4100) SIG_NAME M_F_CPU1_SB_DQ<5>
J 0
(-3365 4110);
DISPLAY 0.659574 (-3365 4110);
PAINT MONO (-3365 4110);
DISPLAY INVISIBLE (-3365 4110);
FORCEPROP 1 LASTPIN (-3375 4100) BN 5
J 0
(-3387 4108);
DISPLAY 0.489362 (-3387 4108);
PAINT GREEN (-3387 4108);
FORCEPROP 2 LAST CDS_LIB mstr_standard
J 0
(-3325 4100);
DISPLAY 0.723404 (-3325 4100);
PAINT MONO (-3325 4100);
DISPLAY INVISIBLE (-3325 4100);
FORCEPROP 1 LAST BODY_TYPE PLUMBING
J 0
(-3325 4150);
DISPLAY 0.872340 (-3325 4150);
PAINT GREEN (-3325 4150);
DISPLAY INVISIBLE (-3325 4150);
FORCEPROP 1 LAST HDL_TAP TRUE
J 0
(-3000 3975);
DISPLAY 0.872340 (-3000 3975);
DISPLAY INVISIBLE (-3000 3975);
FORCEPROP 1 LAST PATH I199
J 0
(-3327 4100);
DISPLAY 0.872340 (-3327 4100);
PAINT GREEN (-3327 4100);
DISPLAY INVISIBLE (-3327 4100);
FORCEADD OFFPAGE..6
R 2
(-2725 2600);
FORCEPROP 2 LAST $XR0 103 
J 0
(-2511 2600);
DISPLAY 0.638298 (-2511 2600);
PAINT MONO (-2511 2600);
FORCEPROP 2 LAST CDS_LIB mstr_standard
J 2
(-2725 2600);
DISPLAY 0.723404 (-2725 2600);
PAINT MONO (-2725 2600);
DISPLAY INVISIBLE (-2725 2600);
FORCEPROP 1 LAST OFFPAGE TRUE
J 2
(-3050 2475);
DISPLAY 0.872340 (-3050 2475);
PAINT GREEN (-3050 2475);
DISPLAY INVISIBLE (-3050 2475);
FORCEPROP 1 LAST COMMENT_BODY TRUE
J 2
(-2825 2525);
DISPLAY 0.872340 (-2825 2525);
PAINT GREEN (-2825 2525);
DISPLAY INVISIBLE (-2825 2525);
FORCEPROP 2 LAST PATH I200
J 0
(-2500 2650);
DISPLAY 1.021277 (-2500 2650);
DISPLAY INVISIBLE (-2500 2650);
FORCEADD OFFPAGE..6
R 2
(-2725 2150);
FORCEPROP 2 LAST $XR0 103 
J 0
(-2511 2150);
DISPLAY 0.638298 (-2511 2150);
PAINT MONO (-2511 2150);
FORCEPROP 2 LAST CDS_LIB mstr_standard
J 2
(-2725 2150);
DISPLAY 0.723404 (-2725 2150);
PAINT MONO (-2725 2150);
DISPLAY INVISIBLE (-2725 2150);
FORCEPROP 1 LAST OFFPAGE TRUE
J 2
(-3050 2025);
DISPLAY 0.872340 (-3050 2025);
PAINT GREEN (-3050 2025);
DISPLAY INVISIBLE (-3050 2025);
FORCEPROP 1 LAST COMMENT_BODY TRUE
J 2
(-2825 2075);
DISPLAY 0.872340 (-2825 2075);
PAINT GREEN (-2825 2075);
DISPLAY INVISIBLE (-2825 2075);
FORCEPROP 2 LAST PATH I201
J 0
(-2500 2200);
DISPLAY 1.021277 (-2500 2200);
DISPLAY INVISIBLE (-2500 2200);
FORCEADD TAP..1
(-3325 4000);
FORCEPROP 3 LASTPIN (-3375 4000) SIG_NAME M_F_CPU1_SB_DQ<7>
J 0
(-3365 4010);
DISPLAY 0.659574 (-3365 4010);
PAINT MONO (-3365 4010);
DISPLAY INVISIBLE (-3365 4010);
FORCEPROP 1 LASTPIN (-3375 4000) BN 7
J 0
(-3387 4008);
DISPLAY 0.489362 (-3387 4008);
PAINT GREEN (-3387 4008);
FORCEPROP 2 LAST CDS_LIB mstr_standard
J 0
(-3325 4000);
DISPLAY 0.723404 (-3325 4000);
PAINT MONO (-3325 4000);
DISPLAY INVISIBLE (-3325 4000);
FORCEPROP 1 LAST BODY_TYPE PLUMBING
J 0
(-3325 4050);
DISPLAY 0.872340 (-3325 4050);
PAINT GREEN (-3325 4050);
DISPLAY INVISIBLE (-3325 4050);
FORCEPROP 1 LAST HDL_TAP TRUE
J 0
(-3000 3875);
DISPLAY 0.872340 (-3000 3875);
DISPLAY INVISIBLE (-3000 3875);
FORCEPROP 1 LAST PATH I202
J 0
(-3327 4000);
DISPLAY 0.872340 (-3327 4000);
PAINT GREEN (-3327 4000);
DISPLAY INVISIBLE (-3327 4000);
FORCEADD TAP..1
(-3325 4050);
FORCEPROP 3 LASTPIN (-3375 4050) SIG_NAME M_F_CPU1_SB_DQ<6>
J 0
(-3365 4060);
DISPLAY 0.659574 (-3365 4060);
PAINT MONO (-3365 4060);
DISPLAY INVISIBLE (-3365 4060);
FORCEPROP 1 LASTPIN (-3375 4050) BN 6
J 0
(-3387 4058);
DISPLAY 0.489362 (-3387 4058);
PAINT GREEN (-3387 4058);
FORCEPROP 2 LAST CDS_LIB mstr_standard
J 0
(-3325 4050);
DISPLAY 0.723404 (-3325 4050);
PAINT MONO (-3325 4050);
DISPLAY INVISIBLE (-3325 4050);
FORCEPROP 1 LAST BODY_TYPE PLUMBING
J 0
(-3325 4100);
DISPLAY 0.872340 (-3325 4100);
PAINT GREEN (-3325 4100);
DISPLAY INVISIBLE (-3325 4100);
FORCEPROP 1 LAST HDL_TAP TRUE
J 0
(-3000 3925);
DISPLAY 0.872340 (-3000 3925);
DISPLAY INVISIBLE (-3000 3925);
FORCEPROP 1 LAST PATH I203
J 0
(-3327 4050);
DISPLAY 0.872340 (-3327 4050);
PAINT GREEN (-3327 4050);
DISPLAY INVISIBLE (-3327 4050);
FORCEADD TAP..1
(-3325 3850);
FORCEPROP 3 LASTPIN (-3375 3850) SIG_NAME M_F_CPU1_SB_DQ<9>
J 0
(-3365 3860);
DISPLAY 0.659574 (-3365 3860);
PAINT MONO (-3365 3860);
DISPLAY INVISIBLE (-3365 3860);
FORCEPROP 1 LASTPIN (-3375 3850) BN 9
J 0
(-3387 3858);
DISPLAY 0.489362 (-3387 3858);
PAINT GREEN (-3387 3858);
FORCEPROP 2 LAST CDS_LIB mstr_standard
J 0
(-3325 3850);
DISPLAY 0.723404 (-3325 3850);
PAINT MONO (-3325 3850);
DISPLAY INVISIBLE (-3325 3850);
FORCEPROP 1 LAST BODY_TYPE PLUMBING
J 0
(-3325 3900);
DISPLAY 0.872340 (-3325 3900);
PAINT GREEN (-3325 3900);
DISPLAY INVISIBLE (-3325 3900);
FORCEPROP 1 LAST HDL_TAP TRUE
J 0
(-3000 3725);
DISPLAY 0.872340 (-3000 3725);
DISPLAY INVISIBLE (-3000 3725);
FORCEPROP 1 LAST PATH I204
J 0
(-3327 3850);
DISPLAY 0.872340 (-3327 3850);
PAINT GREEN (-3327 3850);
DISPLAY INVISIBLE (-3327 3850);
FORCEADD TAP..1
(-3325 3900);
FORCEPROP 3 LASTPIN (-3375 3900) SIG_NAME M_F_CPU1_SB_DQ<8>
J 0
(-3365 3910);
DISPLAY 0.659574 (-3365 3910);
PAINT MONO (-3365 3910);
DISPLAY INVISIBLE (-3365 3910);
FORCEPROP 1 LASTPIN (-3375 3900) BN 8
J 0
(-3387 3908);
DISPLAY 0.489362 (-3387 3908);
PAINT GREEN (-3387 3908);
FORCEPROP 2 LAST CDS_LIB mstr_standard
J 0
(-3325 3900);
DISPLAY 0.723404 (-3325 3900);
PAINT MONO (-3325 3900);
DISPLAY INVISIBLE (-3325 3900);
FORCEPROP 1 LAST BODY_TYPE PLUMBING
J 0
(-3325 3950);
DISPLAY 0.872340 (-3325 3950);
PAINT GREEN (-3325 3950);
DISPLAY INVISIBLE (-3325 3950);
FORCEPROP 1 LAST HDL_TAP TRUE
J 0
(-3000 3775);
DISPLAY 0.872340 (-3000 3775);
DISPLAY INVISIBLE (-3000 3775);
FORCEPROP 1 LAST PATH I205
J 0
(-3327 3900);
DISPLAY 0.872340 (-3327 3900);
PAINT GREEN (-3327 3900);
DISPLAY INVISIBLE (-3327 3900);
FORCEADD TAP..1
(-3325 3800);
FORCEPROP 3 LASTPIN (-3375 3800) SIG_NAME M_F_CPU1_SB_DQ<10>
J 0
(-3365 3810);
DISPLAY 0.659574 (-3365 3810);
PAINT MONO (-3365 3810);
DISPLAY INVISIBLE (-3365 3810);
FORCEPROP 1 LASTPIN (-3375 3800) BN 10
J 0
(-3387 3808);
DISPLAY 0.489362 (-3387 3808);
PAINT GREEN (-3387 3808);
FORCEPROP 2 LAST CDS_LIB mstr_standard
J 0
(-3325 3800);
DISPLAY 0.723404 (-3325 3800);
PAINT MONO (-3325 3800);
DISPLAY INVISIBLE (-3325 3800);
FORCEPROP 1 LAST BODY_TYPE PLUMBING
J 0
(-3325 3850);
DISPLAY 0.872340 (-3325 3850);
PAINT GREEN (-3325 3850);
DISPLAY INVISIBLE (-3325 3850);
FORCEPROP 1 LAST HDL_TAP TRUE
J 0
(-3000 3675);
DISPLAY 0.872340 (-3000 3675);
DISPLAY INVISIBLE (-3000 3675);
FORCEPROP 1 LAST PATH I206
J 0
(-3327 3800);
DISPLAY 0.872340 (-3327 3800);
PAINT GREEN (-3327 3800);
DISPLAY INVISIBLE (-3327 3800);
FORCEADD TAP..1
(-3325 3750);
FORCEPROP 3 LASTPIN (-3375 3750) SIG_NAME M_F_CPU1_SB_DQ<11>
J 0
(-3365 3760);
DISPLAY 0.659574 (-3365 3760);
PAINT MONO (-3365 3760);
DISPLAY INVISIBLE (-3365 3760);
FORCEPROP 1 LASTPIN (-3375 3750) BN 11
J 0
(-3387 3758);
DISPLAY 0.489362 (-3387 3758);
PAINT GREEN (-3387 3758);
FORCEPROP 2 LAST CDS_LIB mstr_standard
J 0
(-3325 3750);
DISPLAY 0.723404 (-3325 3750);
PAINT MONO (-3325 3750);
DISPLAY INVISIBLE (-3325 3750);
FORCEPROP 1 LAST BODY_TYPE PLUMBING
J 0
(-3325 3800);
DISPLAY 0.872340 (-3325 3800);
PAINT GREEN (-3325 3800);
DISPLAY INVISIBLE (-3325 3800);
FORCEPROP 1 LAST HDL_TAP TRUE
J 0
(-3000 3625);
DISPLAY 0.872340 (-3000 3625);
DISPLAY INVISIBLE (-3000 3625);
FORCEPROP 1 LAST PATH I207
J 0
(-3327 3750);
DISPLAY 0.872340 (-3327 3750);
PAINT GREEN (-3327 3750);
DISPLAY INVISIBLE (-3327 3750);
FORCEADD TAP..1
(-3325 3600);
FORCEPROP 3 LASTPIN (-3375 3600) SIG_NAME M_F_CPU1_SB_DQ<14>
J 0
(-3365 3610);
DISPLAY 0.659574 (-3365 3610);
PAINT MONO (-3365 3610);
DISPLAY INVISIBLE (-3365 3610);
FORCEPROP 1 LASTPIN (-3375 3600) BN 14
J 0
(-3387 3608);
DISPLAY 0.489362 (-3387 3608);
PAINT GREEN (-3387 3608);
FORCEPROP 2 LAST CDS_LIB mstr_standard
J 0
(-3325 3600);
DISPLAY 0.723404 (-3325 3600);
PAINT MONO (-3325 3600);
DISPLAY INVISIBLE (-3325 3600);
FORCEPROP 1 LAST BODY_TYPE PLUMBING
J 0
(-3325 3650);
DISPLAY 0.872340 (-3325 3650);
PAINT GREEN (-3325 3650);
DISPLAY INVISIBLE (-3325 3650);
FORCEPROP 1 LAST HDL_TAP TRUE
J 0
(-3000 3475);
DISPLAY 0.872340 (-3000 3475);
DISPLAY INVISIBLE (-3000 3475);
FORCEPROP 1 LAST PATH I208
J 0
(-3327 3600);
DISPLAY 0.872340 (-3327 3600);
PAINT GREEN (-3327 3600);
DISPLAY INVISIBLE (-3327 3600);
FORCEADD TAP..1
(-3325 3700);
FORCEPROP 3 LASTPIN (-3375 3700) SIG_NAME M_F_CPU1_SB_DQ<12>
J 0
(-3365 3710);
DISPLAY 0.659574 (-3365 3710);
PAINT MONO (-3365 3710);
DISPLAY INVISIBLE (-3365 3710);
FORCEPROP 1 LASTPIN (-3375 3700) BN 12
J 0
(-3387 3708);
DISPLAY 0.489362 (-3387 3708);
PAINT GREEN (-3387 3708);
FORCEPROP 2 LAST CDS_LIB mstr_standard
J 0
(-3325 3700);
DISPLAY 0.723404 (-3325 3700);
PAINT MONO (-3325 3700);
DISPLAY INVISIBLE (-3325 3700);
FORCEPROP 1 LAST BODY_TYPE PLUMBING
J 0
(-3325 3750);
DISPLAY 0.872340 (-3325 3750);
PAINT GREEN (-3325 3750);
DISPLAY INVISIBLE (-3325 3750);
FORCEPROP 1 LAST HDL_TAP TRUE
J 0
(-3000 3575);
DISPLAY 0.872340 (-3000 3575);
DISPLAY INVISIBLE (-3000 3575);
FORCEPROP 1 LAST PATH I209
J 0
(-3327 3700);
DISPLAY 0.872340 (-3327 3700);
PAINT GREEN (-3327 3700);
DISPLAY INVISIBLE (-3327 3700);
FORCEADD TAP..1
(-3325 3650);
FORCEPROP 3 LASTPIN (-3375 3650) SIG_NAME M_F_CPU1_SB_DQ<13>
J 0
(-3365 3660);
DISPLAY 0.659574 (-3365 3660);
PAINT MONO (-3365 3660);
DISPLAY INVISIBLE (-3365 3660);
FORCEPROP 1 LASTPIN (-3375 3650) BN 13
J 0
(-3387 3658);
DISPLAY 0.489362 (-3387 3658);
PAINT GREEN (-3387 3658);
FORCEPROP 2 LAST CDS_LIB mstr_standard
J 0
(-3325 3650);
DISPLAY 0.723404 (-3325 3650);
PAINT MONO (-3325 3650);
DISPLAY INVISIBLE (-3325 3650);
FORCEPROP 1 LAST BODY_TYPE PLUMBING
J 0
(-3325 3700);
DISPLAY 0.872340 (-3325 3700);
PAINT GREEN (-3325 3700);
DISPLAY INVISIBLE (-3325 3700);
FORCEPROP 1 LAST HDL_TAP TRUE
J 0
(-3000 3525);
DISPLAY 0.872340 (-3000 3525);
DISPLAY INVISIBLE (-3000 3525);
FORCEPROP 1 LAST PATH I210
J 0
(-3327 3650);
DISPLAY 0.872340 (-3327 3650);
PAINT GREEN (-3327 3650);
DISPLAY INVISIBLE (-3327 3650);
FORCEADD TAP..1
(-3325 3550);
FORCEPROP 3 LASTPIN (-3375 3550) SIG_NAME M_F_CPU1_SB_DQ<15>
J 0
(-3365 3560);
DISPLAY 0.659574 (-3365 3560);
PAINT MONO (-3365 3560);
DISPLAY INVISIBLE (-3365 3560);
FORCEPROP 1 LASTPIN (-3375 3550) BN 15
J 0
(-3387 3558);
DISPLAY 0.489362 (-3387 3558);
PAINT GREEN (-3387 3558);
FORCEPROP 2 LAST CDS_LIB mstr_standard
J 0
(-3325 3550);
DISPLAY 0.723404 (-3325 3550);
PAINT MONO (-3325 3550);
DISPLAY INVISIBLE (-3325 3550);
FORCEPROP 1 LAST BODY_TYPE PLUMBING
J 0
(-3325 3600);
DISPLAY 0.872340 (-3325 3600);
PAINT GREEN (-3325 3600);
DISPLAY INVISIBLE (-3325 3600);
FORCEPROP 1 LAST HDL_TAP TRUE
J 0
(-3000 3425);
DISPLAY 0.872340 (-3000 3425);
DISPLAY INVISIBLE (-3000 3425);
FORCEPROP 1 LAST PATH I211
J 0
(-3327 3550);
DISPLAY 0.872340 (-3327 3550);
PAINT GREEN (-3327 3550);
DISPLAY INVISIBLE (-3327 3550);
FORCEADD TAP..1
(-3325 3450);
FORCEPROP 3 LASTPIN (-3375 3450) SIG_NAME M_F_CPU1_SB_DQ<16>
J 0
(-3365 3460);
DISPLAY 0.659574 (-3365 3460);
PAINT MONO (-3365 3460);
DISPLAY INVISIBLE (-3365 3460);
FORCEPROP 1 LASTPIN (-3375 3450) BN 16
J 0
(-3387 3458);
DISPLAY 0.489362 (-3387 3458);
PAINT GREEN (-3387 3458);
FORCEPROP 2 LAST CDS_LIB mstr_standard
J 0
(-3325 3450);
DISPLAY 0.723404 (-3325 3450);
PAINT MONO (-3325 3450);
DISPLAY INVISIBLE (-3325 3450);
FORCEPROP 1 LAST BODY_TYPE PLUMBING
J 0
(-3325 3500);
DISPLAY 0.872340 (-3325 3500);
PAINT GREEN (-3325 3500);
DISPLAY INVISIBLE (-3325 3500);
FORCEPROP 1 LAST HDL_TAP TRUE
J 0
(-3000 3325);
DISPLAY 0.872340 (-3000 3325);
DISPLAY INVISIBLE (-3000 3325);
FORCEPROP 1 LAST PATH I212
J 0
(-3327 3450);
DISPLAY 0.872340 (-3327 3450);
PAINT GREEN (-3327 3450);
DISPLAY INVISIBLE (-3327 3450);
FORCEADD TAP..1
(-3325 3400);
FORCEPROP 3 LASTPIN (-3375 3400) SIG_NAME M_F_CPU1_SB_DQ<17>
J 0
(-3365 3410);
DISPLAY 0.659574 (-3365 3410);
PAINT MONO (-3365 3410);
DISPLAY INVISIBLE (-3365 3410);
FORCEPROP 1 LASTPIN (-3375 3400) BN 17
J 0
(-3387 3408);
DISPLAY 0.489362 (-3387 3408);
PAINT GREEN (-3387 3408);
FORCEPROP 2 LAST CDS_LIB mstr_standard
J 0
(-3325 3400);
DISPLAY 0.723404 (-3325 3400);
PAINT MONO (-3325 3400);
DISPLAY INVISIBLE (-3325 3400);
FORCEPROP 1 LAST BODY_TYPE PLUMBING
J 0
(-3325 3450);
DISPLAY 0.872340 (-3325 3450);
PAINT GREEN (-3325 3450);
DISPLAY INVISIBLE (-3325 3450);
FORCEPROP 1 LAST HDL_TAP TRUE
J 0
(-3000 3275);
DISPLAY 0.872340 (-3000 3275);
DISPLAY INVISIBLE (-3000 3275);
FORCEPROP 1 LAST PATH I213
J 0
(-3327 3400);
DISPLAY 0.872340 (-3327 3400);
PAINT GREEN (-3327 3400);
DISPLAY INVISIBLE (-3327 3400);
FORCEADD TAP..1
(-3325 3350);
FORCEPROP 3 LASTPIN (-3375 3350) SIG_NAME M_F_CPU1_SB_DQ<18>
J 0
(-3365 3360);
DISPLAY 0.659574 (-3365 3360);
PAINT MONO (-3365 3360);
DISPLAY INVISIBLE (-3365 3360);
FORCEPROP 1 LASTPIN (-3375 3350) BN 18
J 0
(-3387 3358);
DISPLAY 0.489362 (-3387 3358);
PAINT GREEN (-3387 3358);
FORCEPROP 2 LAST CDS_LIB mstr_standard
J 0
(-3325 3350);
DISPLAY 0.723404 (-3325 3350);
PAINT MONO (-3325 3350);
DISPLAY INVISIBLE (-3325 3350);
FORCEPROP 1 LAST BODY_TYPE PLUMBING
J 0
(-3325 3400);
DISPLAY 0.872340 (-3325 3400);
PAINT GREEN (-3325 3400);
DISPLAY INVISIBLE (-3325 3400);
FORCEPROP 1 LAST HDL_TAP TRUE
J 0
(-3000 3225);
DISPLAY 0.872340 (-3000 3225);
DISPLAY INVISIBLE (-3000 3225);
FORCEPROP 1 LAST PATH I214
J 0
(-3327 3350);
DISPLAY 0.872340 (-3327 3350);
PAINT GREEN (-3327 3350);
DISPLAY INVISIBLE (-3327 3350);
FORCEADD TAP..1
(-3325 3250);
FORCEPROP 3 LASTPIN (-3375 3250) SIG_NAME M_F_CPU1_SB_DQ<20>
J 0
(-3365 3260);
DISPLAY 0.659574 (-3365 3260);
PAINT MONO (-3365 3260);
DISPLAY INVISIBLE (-3365 3260);
FORCEPROP 1 LASTPIN (-3375 3250) BN 20
J 0
(-3387 3258);
DISPLAY 0.489362 (-3387 3258);
PAINT GREEN (-3387 3258);
FORCEPROP 2 LAST CDS_LIB mstr_standard
J 0
(-3325 3250);
DISPLAY 0.723404 (-3325 3250);
PAINT MONO (-3325 3250);
DISPLAY INVISIBLE (-3325 3250);
FORCEPROP 1 LAST BODY_TYPE PLUMBING
J 0
(-3325 3300);
DISPLAY 0.872340 (-3325 3300);
PAINT GREEN (-3325 3300);
DISPLAY INVISIBLE (-3325 3300);
FORCEPROP 1 LAST HDL_TAP TRUE
J 0
(-3000 3125);
DISPLAY 0.872340 (-3000 3125);
DISPLAY INVISIBLE (-3000 3125);
FORCEPROP 1 LAST PATH I215
J 0
(-3327 3250);
DISPLAY 0.872340 (-3327 3250);
PAINT GREEN (-3327 3250);
DISPLAY INVISIBLE (-3327 3250);
FORCEADD TAP..1
(-3325 3300);
FORCEPROP 3 LASTPIN (-3375 3300) SIG_NAME M_F_CPU1_SB_DQ<19>
J 0
(-3365 3310);
DISPLAY 0.659574 (-3365 3310);
PAINT MONO (-3365 3310);
DISPLAY INVISIBLE (-3365 3310);
FORCEPROP 1 LASTPIN (-3375 3300) BN 19
J 0
(-3387 3308);
DISPLAY 0.489362 (-3387 3308);
PAINT GREEN (-3387 3308);
FORCEPROP 2 LAST CDS_LIB mstr_standard
J 0
(-3325 3300);
DISPLAY 0.723404 (-3325 3300);
PAINT MONO (-3325 3300);
DISPLAY INVISIBLE (-3325 3300);
FORCEPROP 1 LAST BODY_TYPE PLUMBING
J 0
(-3325 3350);
DISPLAY 0.872340 (-3325 3350);
PAINT GREEN (-3325 3350);
DISPLAY INVISIBLE (-3325 3350);
FORCEPROP 1 LAST HDL_TAP TRUE
J 0
(-3000 3175);
DISPLAY 0.872340 (-3000 3175);
DISPLAY INVISIBLE (-3000 3175);
FORCEPROP 1 LAST PATH I216
J 0
(-3327 3300);
DISPLAY 0.872340 (-3327 3300);
PAINT GREEN (-3327 3300);
DISPLAY INVISIBLE (-3327 3300);
FORCEADD TAP..1
(-3325 3200);
FORCEPROP 3 LASTPIN (-3375 3200) SIG_NAME M_F_CPU1_SB_DQ<21>
J 0
(-3365 3210);
DISPLAY 0.659574 (-3365 3210);
PAINT MONO (-3365 3210);
DISPLAY INVISIBLE (-3365 3210);
FORCEPROP 1 LASTPIN (-3375 3200) BN 21
J 0
(-3387 3208);
DISPLAY 0.489362 (-3387 3208);
PAINT GREEN (-3387 3208);
FORCEPROP 2 LAST CDS_LIB mstr_standard
J 0
(-3325 3200);
DISPLAY 0.723404 (-3325 3200);
PAINT MONO (-3325 3200);
DISPLAY INVISIBLE (-3325 3200);
FORCEPROP 1 LAST BODY_TYPE PLUMBING
J 0
(-3325 3250);
DISPLAY 0.872340 (-3325 3250);
PAINT GREEN (-3325 3250);
DISPLAY INVISIBLE (-3325 3250);
FORCEPROP 1 LAST HDL_TAP TRUE
J 0
(-3000 3075);
DISPLAY 0.872340 (-3000 3075);
DISPLAY INVISIBLE (-3000 3075);
FORCEPROP 1 LAST PATH I217
J 0
(-3327 3200);
DISPLAY 0.872340 (-3327 3200);
PAINT GREEN (-3327 3200);
DISPLAY INVISIBLE (-3327 3200);
FORCEADD TAP..1
(-3325 3100);
FORCEPROP 3 LASTPIN (-3375 3100) SIG_NAME M_F_CPU1_SB_DQ<23>
J 0
(-3365 3110);
DISPLAY 0.659574 (-3365 3110);
PAINT MONO (-3365 3110);
DISPLAY INVISIBLE (-3365 3110);
FORCEPROP 1 LASTPIN (-3375 3100) BN 23
J 0
(-3387 3108);
DISPLAY 0.489362 (-3387 3108);
PAINT GREEN (-3387 3108);
FORCEPROP 2 LAST CDS_LIB mstr_standard
J 0
(-3325 3100);
DISPLAY 0.723404 (-3325 3100);
PAINT MONO (-3325 3100);
DISPLAY INVISIBLE (-3325 3100);
FORCEPROP 1 LAST BODY_TYPE PLUMBING
J 0
(-3325 3150);
DISPLAY 0.872340 (-3325 3150);
PAINT GREEN (-3325 3150);
DISPLAY INVISIBLE (-3325 3150);
FORCEPROP 1 LAST HDL_TAP TRUE
J 0
(-3000 2975);
DISPLAY 0.872340 (-3000 2975);
DISPLAY INVISIBLE (-3000 2975);
FORCEPROP 1 LAST PATH I218
J 0
(-3327 3100);
DISPLAY 0.872340 (-3327 3100);
PAINT GREEN (-3327 3100);
DISPLAY INVISIBLE (-3327 3100);
FORCEADD TAP..1
(-3325 3150);
FORCEPROP 3 LASTPIN (-3375 3150) SIG_NAME M_F_CPU1_SB_DQ<22>
J 0
(-3365 3160);
DISPLAY 0.659574 (-3365 3160);
PAINT MONO (-3365 3160);
DISPLAY INVISIBLE (-3365 3160);
FORCEPROP 1 LASTPIN (-3375 3150) BN 22
J 0
(-3387 3158);
DISPLAY 0.489362 (-3387 3158);
PAINT GREEN (-3387 3158);
FORCEPROP 2 LAST CDS_LIB mstr_standard
J 0
(-3325 3150);
DISPLAY 0.723404 (-3325 3150);
PAINT MONO (-3325 3150);
DISPLAY INVISIBLE (-3325 3150);
FORCEPROP 1 LAST BODY_TYPE PLUMBING
J 0
(-3325 3200);
DISPLAY 0.872340 (-3325 3200);
PAINT GREEN (-3325 3200);
DISPLAY INVISIBLE (-3325 3200);
FORCEPROP 1 LAST HDL_TAP TRUE
J 0
(-3000 3025);
DISPLAY 0.872340 (-3000 3025);
DISPLAY INVISIBLE (-3000 3025);
FORCEPROP 1 LAST PATH I219
J 0
(-3327 3150);
DISPLAY 0.872340 (-3327 3150);
PAINT GREEN (-3327 3150);
DISPLAY INVISIBLE (-3327 3150);
FORCEADD TAP..1
(-3325 3000);
FORCEPROP 3 LASTPIN (-3375 3000) SIG_NAME M_F_CPU1_SB_DQ<24>
J 0
(-3365 3010);
DISPLAY 0.659574 (-3365 3010);
PAINT MONO (-3365 3010);
DISPLAY INVISIBLE (-3365 3010);
FORCEPROP 1 LASTPIN (-3375 3000) BN 24
J 0
(-3387 3008);
DISPLAY 0.489362 (-3387 3008);
PAINT GREEN (-3387 3008);
FORCEPROP 2 LAST CDS_LIB mstr_standard
J 0
(-3325 3000);
DISPLAY 0.723404 (-3325 3000);
PAINT MONO (-3325 3000);
DISPLAY INVISIBLE (-3325 3000);
FORCEPROP 1 LAST BODY_TYPE PLUMBING
J 0
(-3325 3050);
DISPLAY 0.872340 (-3325 3050);
PAINT GREEN (-3325 3050);
DISPLAY INVISIBLE (-3325 3050);
FORCEPROP 1 LAST HDL_TAP TRUE
J 0
(-3000 2875);
DISPLAY 0.872340 (-3000 2875);
DISPLAY INVISIBLE (-3000 2875);
FORCEPROP 1 LAST PATH I220
J 0
(-3327 3000);
DISPLAY 0.872340 (-3327 3000);
PAINT GREEN (-3327 3000);
DISPLAY INVISIBLE (-3327 3000);
FORCEADD TAP..1
(-3325 2950);
FORCEPROP 3 LASTPIN (-3375 2950) SIG_NAME M_F_CPU1_SB_DQ<25>
J 0
(-3365 2960);
DISPLAY 0.659574 (-3365 2960);
PAINT MONO (-3365 2960);
DISPLAY INVISIBLE (-3365 2960);
FORCEPROP 1 LASTPIN (-3375 2950) BN 25
J 0
(-3387 2958);
DISPLAY 0.489362 (-3387 2958);
PAINT GREEN (-3387 2958);
FORCEPROP 2 LAST CDS_LIB mstr_standard
J 0
(-3325 2950);
DISPLAY 0.723404 (-3325 2950);
PAINT MONO (-3325 2950);
DISPLAY INVISIBLE (-3325 2950);
FORCEPROP 1 LAST BODY_TYPE PLUMBING
J 0
(-3325 3000);
DISPLAY 0.872340 (-3325 3000);
PAINT GREEN (-3325 3000);
DISPLAY INVISIBLE (-3325 3000);
FORCEPROP 1 LAST HDL_TAP TRUE
J 0
(-3000 2825);
DISPLAY 0.872340 (-3000 2825);
DISPLAY INVISIBLE (-3000 2825);
FORCEPROP 1 LAST PATH I221
J 0
(-3327 2950);
DISPLAY 0.872340 (-3327 2950);
PAINT GREEN (-3327 2950);
DISPLAY INVISIBLE (-3327 2950);
FORCEADD TAP..1
(-3325 2850);
FORCEPROP 3 LASTPIN (-3375 2850) SIG_NAME M_F_CPU1_SB_DQ<27>
J 0
(-3365 2860);
DISPLAY 0.659574 (-3365 2860);
PAINT MONO (-3365 2860);
DISPLAY INVISIBLE (-3365 2860);
FORCEPROP 1 LASTPIN (-3375 2850) BN 27
J 0
(-3387 2858);
DISPLAY 0.489362 (-3387 2858);
PAINT GREEN (-3387 2858);
FORCEPROP 2 LAST CDS_LIB mstr_standard
J 0
(-3325 2850);
DISPLAY 0.723404 (-3325 2850);
PAINT MONO (-3325 2850);
DISPLAY INVISIBLE (-3325 2850);
FORCEPROP 1 LAST BODY_TYPE PLUMBING
J 0
(-3325 2900);
DISPLAY 0.872340 (-3325 2900);
PAINT GREEN (-3325 2900);
DISPLAY INVISIBLE (-3325 2900);
FORCEPROP 1 LAST HDL_TAP TRUE
J 0
(-3000 2725);
DISPLAY 0.872340 (-3000 2725);
DISPLAY INVISIBLE (-3000 2725);
FORCEPROP 1 LAST PATH I222
J 0
(-3327 2850);
DISPLAY 0.872340 (-3327 2850);
PAINT GREEN (-3327 2850);
DISPLAY INVISIBLE (-3327 2850);
FORCEADD TAP..1
(-3325 2900);
FORCEPROP 3 LASTPIN (-3375 2900) SIG_NAME M_F_CPU1_SB_DQ<26>
J 0
(-3365 2910);
DISPLAY 0.659574 (-3365 2910);
PAINT MONO (-3365 2910);
DISPLAY INVISIBLE (-3365 2910);
FORCEPROP 1 LASTPIN (-3375 2900) BN 26
J 0
(-3387 2908);
DISPLAY 0.489362 (-3387 2908);
PAINT GREEN (-3387 2908);
FORCEPROP 2 LAST CDS_LIB mstr_standard
J 0
(-3325 2900);
DISPLAY 0.723404 (-3325 2900);
PAINT MONO (-3325 2900);
DISPLAY INVISIBLE (-3325 2900);
FORCEPROP 1 LAST BODY_TYPE PLUMBING
J 0
(-3325 2950);
DISPLAY 0.872340 (-3325 2950);
PAINT GREEN (-3325 2950);
DISPLAY INVISIBLE (-3325 2950);
FORCEPROP 1 LAST HDL_TAP TRUE
J 0
(-3000 2775);
DISPLAY 0.872340 (-3000 2775);
DISPLAY INVISIBLE (-3000 2775);
FORCEPROP 1 LAST PATH I223
J 0
(-3327 2900);
DISPLAY 0.872340 (-3327 2900);
PAINT GREEN (-3327 2900);
DISPLAY INVISIBLE (-3327 2900);
FORCEADD TAP..1
(-3325 2750);
FORCEPROP 3 LASTPIN (-3375 2750) SIG_NAME M_F_CPU1_SB_DQ<29>
J 0
(-3365 2760);
DISPLAY 0.659574 (-3365 2760);
PAINT MONO (-3365 2760);
DISPLAY INVISIBLE (-3365 2760);
FORCEPROP 1 LASTPIN (-3375 2750) BN 29
J 0
(-3387 2758);
DISPLAY 0.489362 (-3387 2758);
PAINT GREEN (-3387 2758);
FORCEPROP 2 LAST CDS_LIB mstr_standard
J 0
(-3325 2750);
DISPLAY 0.723404 (-3325 2750);
PAINT MONO (-3325 2750);
DISPLAY INVISIBLE (-3325 2750);
FORCEPROP 1 LAST BODY_TYPE PLUMBING
J 0
(-3325 2800);
DISPLAY 0.872340 (-3325 2800);
PAINT GREEN (-3325 2800);
DISPLAY INVISIBLE (-3325 2800);
FORCEPROP 1 LAST HDL_TAP TRUE
J 0
(-3000 2625);
DISPLAY 0.872340 (-3000 2625);
DISPLAY INVISIBLE (-3000 2625);
FORCEPROP 1 LAST PATH I224
J 0
(-3327 2750);
DISPLAY 0.872340 (-3327 2750);
PAINT GREEN (-3327 2750);
DISPLAY INVISIBLE (-3327 2750);
FORCEADD TAP..1
(-3325 2800);
FORCEPROP 3 LASTPIN (-3375 2800) SIG_NAME M_F_CPU1_SB_DQ<28>
J 0
(-3365 2810);
DISPLAY 0.659574 (-3365 2810);
PAINT MONO (-3365 2810);
DISPLAY INVISIBLE (-3365 2810);
FORCEPROP 1 LASTPIN (-3375 2800) BN 28
J 0
(-3387 2808);
DISPLAY 0.489362 (-3387 2808);
PAINT GREEN (-3387 2808);
FORCEPROP 2 LAST CDS_LIB mstr_standard
J 0
(-3325 2800);
DISPLAY 0.723404 (-3325 2800);
PAINT MONO (-3325 2800);
DISPLAY INVISIBLE (-3325 2800);
FORCEPROP 1 LAST BODY_TYPE PLUMBING
J 0
(-3325 2850);
DISPLAY 0.872340 (-3325 2850);
PAINT GREEN (-3325 2850);
DISPLAY INVISIBLE (-3325 2850);
FORCEPROP 1 LAST HDL_TAP TRUE
J 0
(-3000 2675);
DISPLAY 0.872340 (-3000 2675);
DISPLAY INVISIBLE (-3000 2675);
FORCEPROP 1 LAST PATH I225
J 0
(-3327 2800);
DISPLAY 0.872340 (-3327 2800);
PAINT GREEN (-3327 2800);
DISPLAY INVISIBLE (-3327 2800);
FORCEADD TAP..1
(-3325 2700);
FORCEPROP 3 LASTPIN (-3375 2700) SIG_NAME M_F_CPU1_SB_DQ<30>
J 0
(-3365 2710);
DISPLAY 0.659574 (-3365 2710);
PAINT MONO (-3365 2710);
DISPLAY INVISIBLE (-3365 2710);
FORCEPROP 1 LASTPIN (-3375 2700) BN 30
J 0
(-3387 2708);
DISPLAY 0.489362 (-3387 2708);
PAINT GREEN (-3387 2708);
FORCEPROP 2 LAST CDS_LIB mstr_standard
J 0
(-3325 2700);
DISPLAY 0.723404 (-3325 2700);
PAINT MONO (-3325 2700);
DISPLAY INVISIBLE (-3325 2700);
FORCEPROP 1 LAST BODY_TYPE PLUMBING
J 0
(-3325 2750);
DISPLAY 0.872340 (-3325 2750);
PAINT GREEN (-3325 2750);
DISPLAY INVISIBLE (-3325 2750);
FORCEPROP 1 LAST HDL_TAP TRUE
J 0
(-3000 2575);
DISPLAY 0.872340 (-3000 2575);
DISPLAY INVISIBLE (-3000 2575);
FORCEPROP 1 LAST PATH I226
J 0
(-3327 2700);
DISPLAY 0.872340 (-3327 2700);
PAINT GREEN (-3327 2700);
DISPLAY INVISIBLE (-3327 2700);
FORCEADD TAP..1
(-3325 2650);
FORCEPROP 3 LASTPIN (-3375 2650) SIG_NAME M_F_CPU1_SB_DQ<31>
J 0
(-3365 2660);
DISPLAY 0.659574 (-3365 2660);
PAINT MONO (-3365 2660);
DISPLAY INVISIBLE (-3365 2660);
FORCEPROP 1 LASTPIN (-3375 2650) BN 31
J 0
(-3387 2658);
DISPLAY 0.489362 (-3387 2658);
PAINT GREEN (-3387 2658);
FORCEPROP 2 LAST CDS_LIB mstr_standard
J 0
(-3325 2650);
DISPLAY 0.723404 (-3325 2650);
PAINT MONO (-3325 2650);
DISPLAY INVISIBLE (-3325 2650);
FORCEPROP 1 LAST BODY_TYPE PLUMBING
J 0
(-3325 2700);
DISPLAY 0.872340 (-3325 2700);
PAINT GREEN (-3325 2700);
DISPLAY INVISIBLE (-3325 2700);
FORCEPROP 1 LAST HDL_TAP TRUE
J 0
(-3000 2525);
DISPLAY 0.872340 (-3000 2525);
DISPLAY INVISIBLE (-3000 2525);
FORCEPROP 1 LAST PATH I227
J 0
(-3327 2650);
DISPLAY 0.872340 (-3327 2650);
PAINT GREEN (-3327 2650);
DISPLAY INVISIBLE (-3327 2650);
FORCEADD TAP..1
(-3325 2500);
FORCEPROP 3 LASTPIN (-3375 2500) SIG_NAME M_F_CPU1_SA_CB<1>
J 0
(-3365 2510);
DISPLAY 0.659574 (-3365 2510);
PAINT MONO (-3365 2510);
DISPLAY INVISIBLE (-3365 2510);
FORCEPROP 1 LASTPIN (-3375 2500) BN 1
J 0
(-3387 2508);
DISPLAY 0.489362 (-3387 2508);
PAINT GREEN (-3387 2508);
FORCEPROP 2 LAST CDS_LIB mstr_standard
J 2
(-3325 2500);
DISPLAY 0.723404 (-3325 2500);
PAINT MONO (-3325 2500);
DISPLAY INVISIBLE (-3325 2500);
FORCEPROP 1 LAST BODY_TYPE PLUMBING
J 0
(-3325 2550);
DISPLAY 0.872340 (-3325 2550);
PAINT GREEN (-3325 2550);
DISPLAY INVISIBLE (-3325 2550);
FORCEPROP 1 LAST HDL_TAP TRUE
J 0
(-3000 2375);
DISPLAY 0.872340 (-3000 2375);
DISPLAY INVISIBLE (-3000 2375);
FORCEPROP 1 LAST PATH I228
J 0
(-3327 2500);
DISPLAY 0.872340 (-3327 2500);
PAINT GREEN (-3327 2500);
DISPLAY INVISIBLE (-3327 2500);
FORCEADD TAP..1
(-3325 2450);
FORCEPROP 3 LASTPIN (-3375 2450) SIG_NAME M_F_CPU1_SA_CB<2>
J 0
(-3365 2460);
DISPLAY 0.659574 (-3365 2460);
PAINT MONO (-3365 2460);
DISPLAY INVISIBLE (-3365 2460);
FORCEPROP 1 LASTPIN (-3375 2450) BN 2
J 0
(-3387 2458);
DISPLAY 0.489362 (-3387 2458);
PAINT GREEN (-3387 2458);
FORCEPROP 2 LAST CDS_LIB mstr_standard
J 2
(-3325 2450);
DISPLAY 0.723404 (-3325 2450);
PAINT MONO (-3325 2450);
DISPLAY INVISIBLE (-3325 2450);
FORCEPROP 1 LAST BODY_TYPE PLUMBING
J 0
(-3325 2500);
DISPLAY 0.872340 (-3325 2500);
PAINT GREEN (-3325 2500);
DISPLAY INVISIBLE (-3325 2500);
FORCEPROP 1 LAST HDL_TAP TRUE
J 0
(-3000 2325);
DISPLAY 0.872340 (-3000 2325);
DISPLAY INVISIBLE (-3000 2325);
FORCEPROP 1 LAST PATH I229
J 0
(-3327 2450);
DISPLAY 0.872340 (-3327 2450);
PAINT GREEN (-3327 2450);
DISPLAY INVISIBLE (-3327 2450);
FORCEADD TAP..1
(-3325 2550);
FORCEPROP 3 LASTPIN (-3375 2550) SIG_NAME M_F_CPU1_SA_CB<0>
J 0
(-3365 2560);
DISPLAY 0.659574 (-3365 2560);
PAINT MONO (-3365 2560);
DISPLAY INVISIBLE (-3365 2560);
FORCEPROP 1 LASTPIN (-3375 2550) BN 0
J 0
(-3387 2558);
DISPLAY 0.489362 (-3387 2558);
PAINT GREEN (-3387 2558);
FORCEPROP 2 LAST CDS_LIB mstr_standard
J 2
(-3325 2550);
DISPLAY 0.723404 (-3325 2550);
PAINT MONO (-3325 2550);
DISPLAY INVISIBLE (-3325 2550);
FORCEPROP 1 LAST BODY_TYPE PLUMBING
J 0
(-3325 2600);
DISPLAY 0.872340 (-3325 2600);
PAINT GREEN (-3325 2600);
DISPLAY INVISIBLE (-3325 2600);
FORCEPROP 1 LAST HDL_TAP TRUE
J 0
(-3000 2425);
DISPLAY 0.872340 (-3000 2425);
DISPLAY INVISIBLE (-3000 2425);
FORCEPROP 1 LAST PATH I230
J 0
(-3327 2550);
DISPLAY 0.872340 (-3327 2550);
PAINT GREEN (-3327 2550);
DISPLAY INVISIBLE (-3327 2550);
FORCEADD TAP..1
(-3325 2400);
FORCEPROP 3 LASTPIN (-3375 2400) SIG_NAME M_F_CPU1_SA_CB<3>
J 0
(-3365 2410);
DISPLAY 0.659574 (-3365 2410);
PAINT MONO (-3365 2410);
DISPLAY INVISIBLE (-3365 2410);
FORCEPROP 1 LASTPIN (-3375 2400) BN 3
J 0
(-3387 2408);
DISPLAY 0.489362 (-3387 2408);
PAINT GREEN (-3387 2408);
FORCEPROP 2 LAST CDS_LIB mstr_standard
J 2
(-3325 2400);
DISPLAY 0.723404 (-3325 2400);
PAINT MONO (-3325 2400);
DISPLAY INVISIBLE (-3325 2400);
FORCEPROP 1 LAST BODY_TYPE PLUMBING
J 0
(-3325 2450);
DISPLAY 0.872340 (-3325 2450);
PAINT GREEN (-3325 2450);
DISPLAY INVISIBLE (-3325 2450);
FORCEPROP 1 LAST HDL_TAP TRUE
J 0
(-3000 2275);
DISPLAY 0.872340 (-3000 2275);
DISPLAY INVISIBLE (-3000 2275);
FORCEPROP 1 LAST PATH I231
J 0
(-3327 2400);
DISPLAY 0.872340 (-3327 2400);
PAINT GREEN (-3327 2400);
DISPLAY INVISIBLE (-3327 2400);
FORCEADD TAP..1
(-3325 2350);
FORCEPROP 3 LASTPIN (-3375 2350) SIG_NAME M_F_CPU1_SA_CB<4>
J 0
(-3365 2360);
DISPLAY 0.659574 (-3365 2360);
PAINT MONO (-3365 2360);
DISPLAY INVISIBLE (-3365 2360);
FORCEPROP 1 LASTPIN (-3375 2350) BN 4
J 0
(-3387 2358);
DISPLAY 0.489362 (-3387 2358);
PAINT GREEN (-3387 2358);
FORCEPROP 2 LAST CDS_LIB mstr_standard
J 2
(-3325 2350);
DISPLAY 0.723404 (-3325 2350);
PAINT MONO (-3325 2350);
DISPLAY INVISIBLE (-3325 2350);
FORCEPROP 1 LAST BODY_TYPE PLUMBING
J 0
(-3325 2400);
DISPLAY 0.872340 (-3325 2400);
PAINT GREEN (-3325 2400);
DISPLAY INVISIBLE (-3325 2400);
FORCEPROP 1 LAST HDL_TAP TRUE
J 0
(-3000 2225);
DISPLAY 0.872340 (-3000 2225);
DISPLAY INVISIBLE (-3000 2225);
FORCEPROP 1 LAST PATH I232
J 0
(-3327 2350);
DISPLAY 0.872340 (-3327 2350);
PAINT GREEN (-3327 2350);
DISPLAY INVISIBLE (-3327 2350);
FORCEADD TAP..1
(-3325 2200);
FORCEPROP 3 LASTPIN (-3375 2200) SIG_NAME M_F_CPU1_SA_CB<7>
J 0
(-3365 2210);
DISPLAY 0.659574 (-3365 2210);
PAINT MONO (-3365 2210);
DISPLAY INVISIBLE (-3365 2210);
FORCEPROP 1 LASTPIN (-3375 2200) BN 7
J 0
(-3387 2208);
DISPLAY 0.489362 (-3387 2208);
PAINT GREEN (-3387 2208);
FORCEPROP 2 LAST CDS_LIB mstr_standard
J 2
(-3325 2200);
DISPLAY 0.723404 (-3325 2200);
PAINT MONO (-3325 2200);
DISPLAY INVISIBLE (-3325 2200);
FORCEPROP 1 LAST BODY_TYPE PLUMBING
J 0
(-3325 2250);
DISPLAY 0.872340 (-3325 2250);
PAINT GREEN (-3325 2250);
DISPLAY INVISIBLE (-3325 2250);
FORCEPROP 1 LAST HDL_TAP TRUE
J 0
(-3000 2075);
DISPLAY 0.872340 (-3000 2075);
DISPLAY INVISIBLE (-3000 2075);
FORCEPROP 1 LAST PATH I233
J 0
(-3327 2200);
DISPLAY 0.872340 (-3327 2200);
PAINT GREEN (-3327 2200);
DISPLAY INVISIBLE (-3327 2200);
FORCEADD TAP..1
(-3325 2300);
FORCEPROP 3 LASTPIN (-3375 2300) SIG_NAME M_F_CPU1_SA_CB<5>
J 0
(-3365 2310);
DISPLAY 0.659574 (-3365 2310);
PAINT MONO (-3365 2310);
DISPLAY INVISIBLE (-3365 2310);
FORCEPROP 1 LASTPIN (-3375 2300) BN 5
J 0
(-3387 2308);
DISPLAY 0.489362 (-3387 2308);
PAINT GREEN (-3387 2308);
FORCEPROP 2 LAST CDS_LIB mstr_standard
J 2
(-3325 2300);
DISPLAY 0.723404 (-3325 2300);
PAINT MONO (-3325 2300);
DISPLAY INVISIBLE (-3325 2300);
FORCEPROP 1 LAST BODY_TYPE PLUMBING
J 0
(-3325 2350);
DISPLAY 0.872340 (-3325 2350);
PAINT GREEN (-3325 2350);
DISPLAY INVISIBLE (-3325 2350);
FORCEPROP 1 LAST HDL_TAP TRUE
J 0
(-3000 2175);
DISPLAY 0.872340 (-3000 2175);
DISPLAY INVISIBLE (-3000 2175);
FORCEPROP 1 LAST PATH I234
J 0
(-3327 2300);
DISPLAY 0.872340 (-3327 2300);
PAINT GREEN (-3327 2300);
DISPLAY INVISIBLE (-3327 2300);
FORCEADD TAP..1
(-3325 2250);
FORCEPROP 3 LASTPIN (-3375 2250) SIG_NAME M_F_CPU1_SA_CB<6>
J 0
(-3365 2260);
DISPLAY 0.659574 (-3365 2260);
PAINT MONO (-3365 2260);
DISPLAY INVISIBLE (-3365 2260);
FORCEPROP 1 LASTPIN (-3375 2250) BN 6
J 0
(-3387 2258);
DISPLAY 0.489362 (-3387 2258);
PAINT GREEN (-3387 2258);
FORCEPROP 2 LAST CDS_LIB mstr_standard
J 2
(-3325 2250);
DISPLAY 0.723404 (-3325 2250);
PAINT MONO (-3325 2250);
DISPLAY INVISIBLE (-3325 2250);
FORCEPROP 1 LAST BODY_TYPE PLUMBING
J 0
(-3325 2300);
DISPLAY 0.872340 (-3325 2300);
PAINT GREEN (-3325 2300);
DISPLAY INVISIBLE (-3325 2300);
FORCEPROP 1 LAST HDL_TAP TRUE
J 0
(-3000 2125);
DISPLAY 0.872340 (-3000 2125);
DISPLAY INVISIBLE (-3000 2125);
FORCEPROP 1 LAST PATH I235
J 0
(-3327 2250);
DISPLAY 0.872340 (-3327 2250);
PAINT GREEN (-3327 2250);
DISPLAY INVISIBLE (-3327 2250);
FORCEADD TAP..1
(-3325 2050);
FORCEPROP 3 LASTPIN (-3375 2050) SIG_NAME M_F_CPU1_SB_CB<1>
J 0
(-3365 2060);
DISPLAY 0.659574 (-3365 2060);
PAINT MONO (-3365 2060);
DISPLAY INVISIBLE (-3365 2060);
FORCEPROP 1 LASTPIN (-3375 2050) BN 1
J 0
(-3387 2058);
DISPLAY 0.489362 (-3387 2058);
PAINT GREEN (-3387 2058);
FORCEPROP 2 LAST CDS_LIB mstr_standard
J 2
(-3325 2050);
DISPLAY 0.723404 (-3325 2050);
PAINT MONO (-3325 2050);
DISPLAY INVISIBLE (-3325 2050);
FORCEPROP 1 LAST BODY_TYPE PLUMBING
J 0
(-3325 2100);
DISPLAY 0.872340 (-3325 2100);
PAINT GREEN (-3325 2100);
DISPLAY INVISIBLE (-3325 2100);
FORCEPROP 1 LAST HDL_TAP TRUE
J 0
(-3000 1925);
DISPLAY 0.872340 (-3000 1925);
DISPLAY INVISIBLE (-3000 1925);
FORCEPROP 1 LAST PATH I236
J 0
(-3327 2050);
DISPLAY 0.872340 (-3327 2050);
PAINT GREEN (-3327 2050);
DISPLAY INVISIBLE (-3327 2050);
FORCEADD TAP..1
(-3325 2100);
FORCEPROP 3 LASTPIN (-3375 2100) SIG_NAME M_F_CPU1_SB_CB<0>
J 0
(-3365 2110);
DISPLAY 0.659574 (-3365 2110);
PAINT MONO (-3365 2110);
DISPLAY INVISIBLE (-3365 2110);
FORCEPROP 1 LASTPIN (-3375 2100) BN 0
J 0
(-3387 2108);
DISPLAY 0.489362 (-3387 2108);
PAINT GREEN (-3387 2108);
FORCEPROP 2 LAST CDS_LIB mstr_standard
J 2
(-3325 2100);
DISPLAY 0.723404 (-3325 2100);
PAINT MONO (-3325 2100);
DISPLAY INVISIBLE (-3325 2100);
FORCEPROP 1 LAST BODY_TYPE PLUMBING
J 0
(-3325 2150);
DISPLAY 0.872340 (-3325 2150);
PAINT GREEN (-3325 2150);
DISPLAY INVISIBLE (-3325 2150);
FORCEPROP 1 LAST HDL_TAP TRUE
J 0
(-3000 1975);
DISPLAY 0.872340 (-3000 1975);
DISPLAY INVISIBLE (-3000 1975);
FORCEPROP 1 LAST PATH I237
J 0
(-3327 2100);
DISPLAY 0.872340 (-3327 2100);
PAINT GREEN (-3327 2100);
DISPLAY INVISIBLE (-3327 2100);
FORCEADD TAP..1
(-3325 2000);
FORCEPROP 3 LASTPIN (-3375 2000) SIG_NAME M_F_CPU1_SB_CB<2>
J 0
(-3365 2010);
DISPLAY 0.659574 (-3365 2010);
PAINT MONO (-3365 2010);
DISPLAY INVISIBLE (-3365 2010);
FORCEPROP 1 LASTPIN (-3375 2000) BN 2
J 0
(-3387 2008);
DISPLAY 0.489362 (-3387 2008);
PAINT GREEN (-3387 2008);
FORCEPROP 2 LAST CDS_LIB mstr_standard
J 2
(-3325 2000);
DISPLAY 0.723404 (-3325 2000);
PAINT MONO (-3325 2000);
DISPLAY INVISIBLE (-3325 2000);
FORCEPROP 1 LAST BODY_TYPE PLUMBING
J 0
(-3325 2050);
DISPLAY 0.872340 (-3325 2050);
PAINT GREEN (-3325 2050);
DISPLAY INVISIBLE (-3325 2050);
FORCEPROP 1 LAST HDL_TAP TRUE
J 0
(-3000 1875);
DISPLAY 0.872340 (-3000 1875);
DISPLAY INVISIBLE (-3000 1875);
FORCEPROP 1 LAST PATH I238
J 0
(-3327 2000);
DISPLAY 0.872340 (-3327 2000);
PAINT GREEN (-3327 2000);
DISPLAY INVISIBLE (-3327 2000);
FORCEADD TAP..1
(-3325 1950);
FORCEPROP 3 LASTPIN (-3375 1950) SIG_NAME M_F_CPU1_SB_CB<3>
J 0
(-3365 1960);
DISPLAY 0.659574 (-3365 1960);
PAINT MONO (-3365 1960);
DISPLAY INVISIBLE (-3365 1960);
FORCEPROP 1 LASTPIN (-3375 1950) BN 3
J 0
(-3387 1958);
DISPLAY 0.489362 (-3387 1958);
PAINT GREEN (-3387 1958);
FORCEPROP 2 LAST CDS_LIB mstr_standard
J 2
(-3325 1950);
DISPLAY 0.723404 (-3325 1950);
PAINT MONO (-3325 1950);
DISPLAY INVISIBLE (-3325 1950);
FORCEPROP 1 LAST BODY_TYPE PLUMBING
J 0
(-3325 2000);
DISPLAY 0.872340 (-3325 2000);
PAINT GREEN (-3325 2000);
DISPLAY INVISIBLE (-3325 2000);
FORCEPROP 1 LAST HDL_TAP TRUE
J 0
(-3000 1825);
DISPLAY 0.872340 (-3000 1825);
DISPLAY INVISIBLE (-3000 1825);
FORCEPROP 1 LAST PATH I239
J 0
(-3327 1950);
DISPLAY 0.872340 (-3327 1950);
PAINT GREEN (-3327 1950);
DISPLAY INVISIBLE (-3327 1950);
FORCEADD TAP..1
(-3325 1800);
FORCEPROP 3 LASTPIN (-3375 1800) SIG_NAME M_F_CPU1_SB_CB<6>
J 0
(-3365 1810);
DISPLAY 0.659574 (-3365 1810);
PAINT MONO (-3365 1810);
DISPLAY INVISIBLE (-3365 1810);
FORCEPROP 1 LASTPIN (-3375 1800) BN 6
J 0
(-3387 1808);
DISPLAY 0.489362 (-3387 1808);
PAINT GREEN (-3387 1808);
FORCEPROP 2 LAST CDS_LIB mstr_standard
J 2
(-3325 1800);
DISPLAY 0.723404 (-3325 1800);
PAINT MONO (-3325 1800);
DISPLAY INVISIBLE (-3325 1800);
FORCEPROP 1 LAST BODY_TYPE PLUMBING
J 0
(-3325 1850);
DISPLAY 0.872340 (-3325 1850);
PAINT GREEN (-3325 1850);
DISPLAY INVISIBLE (-3325 1850);
FORCEPROP 1 LAST HDL_TAP TRUE
J 0
(-3000 1675);
DISPLAY 0.872340 (-3000 1675);
DISPLAY INVISIBLE (-3000 1675);
FORCEPROP 1 LAST PATH I240
J 0
(-3327 1800);
DISPLAY 0.872340 (-3327 1800);
PAINT GREEN (-3327 1800);
DISPLAY INVISIBLE (-3327 1800);
FORCEADD TAP..1
(-3325 1900);
FORCEPROP 3 LASTPIN (-3375 1900) SIG_NAME M_F_CPU1_SB_CB<4>
J 0
(-3365 1910);
DISPLAY 0.659574 (-3365 1910);
PAINT MONO (-3365 1910);
DISPLAY INVISIBLE (-3365 1910);
FORCEPROP 1 LASTPIN (-3375 1900) BN 4
J 0
(-3387 1908);
DISPLAY 0.489362 (-3387 1908);
PAINT GREEN (-3387 1908);
FORCEPROP 2 LAST CDS_LIB mstr_standard
J 2
(-3325 1900);
DISPLAY 0.723404 (-3325 1900);
PAINT MONO (-3325 1900);
DISPLAY INVISIBLE (-3325 1900);
FORCEPROP 1 LAST BODY_TYPE PLUMBING
J 0
(-3325 1950);
DISPLAY 0.872340 (-3325 1950);
PAINT GREEN (-3325 1950);
DISPLAY INVISIBLE (-3325 1950);
FORCEPROP 1 LAST HDL_TAP TRUE
J 0
(-3000 1775);
DISPLAY 0.872340 (-3000 1775);
DISPLAY INVISIBLE (-3000 1775);
FORCEPROP 1 LAST PATH I241
J 0
(-3327 1900);
DISPLAY 0.872340 (-3327 1900);
PAINT GREEN (-3327 1900);
DISPLAY INVISIBLE (-3327 1900);
FORCEADD TAP..1
(-3325 1850);
FORCEPROP 3 LASTPIN (-3375 1850) SIG_NAME M_F_CPU1_SB_CB<5>
J 0
(-3365 1860);
DISPLAY 0.659574 (-3365 1860);
PAINT MONO (-3365 1860);
DISPLAY INVISIBLE (-3365 1860);
FORCEPROP 1 LASTPIN (-3375 1850) BN 5
J 0
(-3387 1858);
DISPLAY 0.489362 (-3387 1858);
PAINT GREEN (-3387 1858);
FORCEPROP 2 LAST CDS_LIB mstr_standard
J 2
(-3325 1850);
DISPLAY 0.723404 (-3325 1850);
PAINT MONO (-3325 1850);
DISPLAY INVISIBLE (-3325 1850);
FORCEPROP 1 LAST BODY_TYPE PLUMBING
J 0
(-3325 1900);
DISPLAY 0.872340 (-3325 1900);
PAINT GREEN (-3325 1900);
DISPLAY INVISIBLE (-3325 1900);
FORCEPROP 1 LAST HDL_TAP TRUE
J 0
(-3000 1725);
DISPLAY 0.872340 (-3000 1725);
DISPLAY INVISIBLE (-3000 1725);
FORCEPROP 1 LAST PATH I242
J 0
(-3327 1850);
DISPLAY 0.872340 (-3327 1850);
PAINT GREEN (-3327 1850);
DISPLAY INVISIBLE (-3327 1850);
FORCEADD TAP..1
(-3325 1750);
FORCEPROP 3 LASTPIN (-3375 1750) SIG_NAME M_F_CPU1_SB_CB<7>
J 0
(-3365 1760);
DISPLAY 0.659574 (-3365 1760);
PAINT MONO (-3365 1760);
DISPLAY INVISIBLE (-3365 1760);
FORCEPROP 1 LASTPIN (-3375 1750) BN 7
J 0
(-3387 1758);
DISPLAY 0.489362 (-3387 1758);
PAINT GREEN (-3387 1758);
FORCEPROP 2 LAST CDS_LIB mstr_standard
J 2
(-3325 1750);
DISPLAY 0.723404 (-3325 1750);
PAINT MONO (-3325 1750);
DISPLAY INVISIBLE (-3325 1750);
FORCEPROP 1 LAST BODY_TYPE PLUMBING
J 0
(-3325 1800);
DISPLAY 0.872340 (-3325 1800);
PAINT GREEN (-3325 1800);
DISPLAY INVISIBLE (-3325 1800);
FORCEPROP 1 LAST HDL_TAP TRUE
J 0
(-3000 1625);
DISPLAY 0.872340 (-3000 1625);
DISPLAY INVISIBLE (-3000 1625);
FORCEPROP 1 LAST PATH I243
J 0
(-3327 1750);
DISPLAY 0.872340 (-3327 1750);
PAINT GREEN (-3327 1750);
DISPLAY INVISIBLE (-3327 1750);
FORCEADD TAP..1
R 2
(-5750 6150);
FORCEPROP 3 LASTPIN (-5700 6150) SIG_NAME M_F_CPU1_SA_DQS_DP<0>
J 0
(-5690 6160);
DISPLAY 0.659574 (-5690 6160);
PAINT MONO (-5690 6160);
DISPLAY INVISIBLE (-5690 6160);
FORCEPROP 1 LASTPIN (-5700 6150) BN 0
J 2
(-5688 6158);
DISPLAY 0.489362 (-5688 6158);
PAINT GREEN (-5688 6158);
FORCEPROP 2 LAST CDS_LIB mstr_standard
J 2
(-5750 6150);
DISPLAY 0.723404 (-5750 6150);
PAINT MONO (-5750 6150);
DISPLAY INVISIBLE (-5750 6150);
FORCEPROP 1 LAST BODY_TYPE PLUMBING
J 2
(-5750 6200);
DISPLAY 0.872340 (-5750 6200);
PAINT GREEN (-5750 6200);
DISPLAY INVISIBLE (-5750 6200);
FORCEPROP 1 LAST HDL_TAP TRUE
J 2
(-6075 6025);
DISPLAY 0.872340 (-6075 6025);
DISPLAY INVISIBLE (-6075 6025);
FORCEPROP 1 LAST PATH I244
J 2
(-5748 6150);
DISPLAY 0.872340 (-5748 6150);
PAINT GREEN (-5748 6150);
DISPLAY INVISIBLE (-5748 6150);
FORCEADD TAP..1
R 2
(-5750 6050);
FORCEPROP 3 LASTPIN (-5700 6050) SIG_NAME M_F_CPU1_SA_DQS_DP<1>
J 0
(-5690 6060);
DISPLAY 0.659574 (-5690 6060);
PAINT MONO (-5690 6060);
DISPLAY INVISIBLE (-5690 6060);
FORCEPROP 1 LASTPIN (-5700 6050) BN 1
J 2
(-5688 6058);
DISPLAY 0.489362 (-5688 6058);
PAINT GREEN (-5688 6058);
FORCEPROP 2 LAST CDS_LIB mstr_standard
J 2
(-5750 6050);
DISPLAY 0.723404 (-5750 6050);
PAINT MONO (-5750 6050);
DISPLAY INVISIBLE (-5750 6050);
FORCEPROP 1 LAST BODY_TYPE PLUMBING
J 2
(-5750 6100);
DISPLAY 0.872340 (-5750 6100);
PAINT GREEN (-5750 6100);
DISPLAY INVISIBLE (-5750 6100);
FORCEPROP 1 LAST HDL_TAP TRUE
J 2
(-6075 5925);
DISPLAY 0.872340 (-6075 5925);
DISPLAY INVISIBLE (-6075 5925);
FORCEPROP 1 LAST PATH I245
J 2
(-5748 6050);
DISPLAY 0.872340 (-5748 6050);
PAINT GREEN (-5748 6050);
DISPLAY INVISIBLE (-5748 6050);
FORCEADD TAP..1
R 2
(-5750 5950);
FORCEPROP 3 LASTPIN (-5700 5950) SIG_NAME M_F_CPU1_SA_DQS_DP<2>
J 0
(-5690 5960);
DISPLAY 0.659574 (-5690 5960);
PAINT MONO (-5690 5960);
DISPLAY INVISIBLE (-5690 5960);
FORCEPROP 1 LASTPIN (-5700 5950) BN 2
J 2
(-5688 5958);
DISPLAY 0.489362 (-5688 5958);
PAINT GREEN (-5688 5958);
FORCEPROP 2 LAST CDS_LIB mstr_standard
J 2
(-5750 5950);
DISPLAY 0.723404 (-5750 5950);
PAINT MONO (-5750 5950);
DISPLAY INVISIBLE (-5750 5950);
FORCEPROP 1 LAST BODY_TYPE PLUMBING
J 2
(-5750 6000);
DISPLAY 0.872340 (-5750 6000);
PAINT GREEN (-5750 6000);
DISPLAY INVISIBLE (-5750 6000);
FORCEPROP 1 LAST HDL_TAP TRUE
J 2
(-6075 5825);
DISPLAY 0.872340 (-6075 5825);
DISPLAY INVISIBLE (-6075 5825);
FORCEPROP 1 LAST PATH I246
J 2
(-5748 5950);
DISPLAY 0.872340 (-5748 5950);
PAINT GREEN (-5748 5950);
DISPLAY INVISIBLE (-5748 5950);
FORCEADD TAP..1
R 2
(-5750 5850);
FORCEPROP 3 LASTPIN (-5700 5850) SIG_NAME M_F_CPU1_SA_DQS_DP<3>
J 0
(-5690 5860);
DISPLAY 0.659574 (-5690 5860);
PAINT MONO (-5690 5860);
DISPLAY INVISIBLE (-5690 5860);
FORCEPROP 1 LASTPIN (-5700 5850) BN 3
J 2
(-5688 5858);
DISPLAY 0.489362 (-5688 5858);
PAINT GREEN (-5688 5858);
FORCEPROP 2 LAST CDS_LIB mstr_standard
J 2
(-5750 5850);
DISPLAY 0.723404 (-5750 5850);
PAINT MONO (-5750 5850);
DISPLAY INVISIBLE (-5750 5850);
FORCEPROP 1 LAST BODY_TYPE PLUMBING
J 2
(-5750 5900);
DISPLAY 0.872340 (-5750 5900);
PAINT GREEN (-5750 5900);
DISPLAY INVISIBLE (-5750 5900);
FORCEPROP 1 LAST HDL_TAP TRUE
J 2
(-6075 5725);
DISPLAY 0.872340 (-6075 5725);
DISPLAY INVISIBLE (-6075 5725);
FORCEPROP 1 LAST PATH I247
J 2
(-5748 5850);
DISPLAY 0.872340 (-5748 5850);
PAINT GREEN (-5748 5850);
DISPLAY INVISIBLE (-5748 5850);
FORCEADD TAP..1
R 2
(-5750 5650);
FORCEPROP 3 LASTPIN (-5700 5650) SIG_NAME M_F_CPU1_SA_DQS_DP<5>
J 0
(-5690 5660);
DISPLAY 0.659574 (-5690 5660);
PAINT MONO (-5690 5660);
DISPLAY INVISIBLE (-5690 5660);
FORCEPROP 1 LASTPIN (-5700 5650) BN 5
J 2
(-5688 5658);
DISPLAY 0.489362 (-5688 5658);
PAINT GREEN (-5688 5658);
FORCEPROP 2 LAST CDS_LIB mstr_standard
J 2
(-5750 5650);
DISPLAY 0.723404 (-5750 5650);
PAINT MONO (-5750 5650);
DISPLAY INVISIBLE (-5750 5650);
FORCEPROP 1 LAST BODY_TYPE PLUMBING
J 2
(-5750 5700);
DISPLAY 0.872340 (-5750 5700);
PAINT GREEN (-5750 5700);
DISPLAY INVISIBLE (-5750 5700);
FORCEPROP 1 LAST HDL_TAP TRUE
J 2
(-6075 5525);
DISPLAY 0.872340 (-6075 5525);
DISPLAY INVISIBLE (-6075 5525);
FORCEPROP 1 LAST PATH I248
J 2
(-5748 5650);
DISPLAY 0.872340 (-5748 5650);
PAINT GREEN (-5748 5650);
DISPLAY INVISIBLE (-5748 5650);
FORCEADD TAP..1
R 2
(-5750 5750);
FORCEPROP 3 LASTPIN (-5700 5750) SIG_NAME M_F_CPU1_SA_DQS_DP<4>
J 0
(-5690 5760);
DISPLAY 0.659574 (-5690 5760);
PAINT MONO (-5690 5760);
DISPLAY INVISIBLE (-5690 5760);
FORCEPROP 1 LASTPIN (-5700 5750) BN 4
J 2
(-5688 5758);
DISPLAY 0.489362 (-5688 5758);
PAINT GREEN (-5688 5758);
FORCEPROP 2 LAST CDS_LIB mstr_standard
J 2
(-5750 5750);
DISPLAY 0.723404 (-5750 5750);
PAINT MONO (-5750 5750);
DISPLAY INVISIBLE (-5750 5750);
FORCEPROP 1 LAST BODY_TYPE PLUMBING
J 2
(-5750 5800);
DISPLAY 0.872340 (-5750 5800);
PAINT GREEN (-5750 5800);
DISPLAY INVISIBLE (-5750 5800);
FORCEPROP 1 LAST HDL_TAP TRUE
J 2
(-6075 5625);
DISPLAY 0.872340 (-6075 5625);
DISPLAY INVISIBLE (-6075 5625);
FORCEPROP 1 LAST PATH I249
J 2
(-5748 5750);
DISPLAY 0.872340 (-5748 5750);
PAINT GREEN (-5748 5750);
DISPLAY INVISIBLE (-5748 5750);
FORCEADD TAP..1
R 2
(-5950 6100);
FORCEPROP 3 LASTPIN (-5900 6100) SIG_NAME M_F_CPU1_SA_DQS_DN<0>
J 0
(-5890 6110);
DISPLAY 0.659574 (-5890 6110);
PAINT MONO (-5890 6110);
DISPLAY INVISIBLE (-5890 6110);
FORCEPROP 1 LASTPIN (-5900 6100) BN 0
J 2
(-5888 6108);
DISPLAY 0.489362 (-5888 6108);
PAINT GREEN (-5888 6108);
FORCEPROP 2 LAST CDS_LIB mstr_standard
J 2
(-5950 6100);
DISPLAY 0.723404 (-5950 6100);
PAINT MONO (-5950 6100);
DISPLAY INVISIBLE (-5950 6100);
FORCEPROP 1 LAST BODY_TYPE PLUMBING
J 2
(-5950 6150);
DISPLAY 0.872340 (-5950 6150);
PAINT GREEN (-5950 6150);
DISPLAY INVISIBLE (-5950 6150);
FORCEPROP 1 LAST HDL_TAP TRUE
J 2
(-6275 5975);
DISPLAY 0.872340 (-6275 5975);
DISPLAY INVISIBLE (-6275 5975);
FORCEPROP 1 LAST PATH I250
J 2
(-5948 6100);
DISPLAY 0.872340 (-5948 6100);
PAINT GREEN (-5948 6100);
DISPLAY INVISIBLE (-5948 6100);
FORCEADD TAP..1
R 2
(-5950 6000);
FORCEPROP 3 LASTPIN (-5900 6000) SIG_NAME M_F_CPU1_SA_DQS_DN<1>
J 0
(-5890 6010);
DISPLAY 0.659574 (-5890 6010);
PAINT MONO (-5890 6010);
DISPLAY INVISIBLE (-5890 6010);
FORCEPROP 1 LASTPIN (-5900 6000) BN 1
J 2
(-5888 6008);
DISPLAY 0.489362 (-5888 6008);
PAINT GREEN (-5888 6008);
FORCEPROP 2 LAST CDS_LIB mstr_standard
J 2
(-5950 6000);
DISPLAY 0.723404 (-5950 6000);
PAINT MONO (-5950 6000);
DISPLAY INVISIBLE (-5950 6000);
FORCEPROP 1 LAST BODY_TYPE PLUMBING
J 2
(-5950 6050);
DISPLAY 0.872340 (-5950 6050);
PAINT GREEN (-5950 6050);
DISPLAY INVISIBLE (-5950 6050);
FORCEPROP 1 LAST HDL_TAP TRUE
J 2
(-6275 5875);
DISPLAY 0.872340 (-6275 5875);
DISPLAY INVISIBLE (-6275 5875);
FORCEPROP 1 LAST PATH I251
J 2
(-5948 6000);
DISPLAY 0.872340 (-5948 6000);
PAINT GREEN (-5948 6000);
DISPLAY INVISIBLE (-5948 6000);
FORCEADD TAP..1
R 2
(-5950 5900);
FORCEPROP 3 LASTPIN (-5900 5900) SIG_NAME M_F_CPU1_SA_DQS_DN<2>
J 0
(-5890 5910);
DISPLAY 0.659574 (-5890 5910);
PAINT MONO (-5890 5910);
DISPLAY INVISIBLE (-5890 5910);
FORCEPROP 1 LASTPIN (-5900 5900) BN 2
J 2
(-5888 5908);
DISPLAY 0.489362 (-5888 5908);
PAINT GREEN (-5888 5908);
FORCEPROP 2 LAST CDS_LIB mstr_standard
J 2
(-5950 5900);
DISPLAY 0.723404 (-5950 5900);
PAINT MONO (-5950 5900);
DISPLAY INVISIBLE (-5950 5900);
FORCEPROP 1 LAST BODY_TYPE PLUMBING
J 2
(-5950 5950);
DISPLAY 0.872340 (-5950 5950);
PAINT GREEN (-5950 5950);
DISPLAY INVISIBLE (-5950 5950);
FORCEPROP 1 LAST HDL_TAP TRUE
J 2
(-6275 5775);
DISPLAY 0.872340 (-6275 5775);
DISPLAY INVISIBLE (-6275 5775);
FORCEPROP 1 LAST PATH I252
J 2
(-5948 5900);
DISPLAY 0.872340 (-5948 5900);
PAINT GREEN (-5948 5900);
DISPLAY INVISIBLE (-5948 5900);
FORCEADD TAP..1
R 2
(-5950 5800);
FORCEPROP 3 LASTPIN (-5900 5800) SIG_NAME M_F_CPU1_SA_DQS_DN<3>
J 0
(-5890 5810);
DISPLAY 0.659574 (-5890 5810);
PAINT MONO (-5890 5810);
DISPLAY INVISIBLE (-5890 5810);
FORCEPROP 1 LASTPIN (-5900 5800) BN 3
J 2
(-5888 5808);
DISPLAY 0.489362 (-5888 5808);
PAINT GREEN (-5888 5808);
FORCEPROP 2 LAST CDS_LIB mstr_standard
J 2
(-5950 5800);
DISPLAY 0.723404 (-5950 5800);
PAINT MONO (-5950 5800);
DISPLAY INVISIBLE (-5950 5800);
FORCEPROP 1 LAST BODY_TYPE PLUMBING
J 2
(-5950 5850);
DISPLAY 0.872340 (-5950 5850);
PAINT GREEN (-5950 5850);
DISPLAY INVISIBLE (-5950 5850);
FORCEPROP 1 LAST HDL_TAP TRUE
J 2
(-6275 5675);
DISPLAY 0.872340 (-6275 5675);
DISPLAY INVISIBLE (-6275 5675);
FORCEPROP 1 LAST PATH I253
J 2
(-5948 5800);
DISPLAY 0.872340 (-5948 5800);
PAINT GREEN (-5948 5800);
DISPLAY INVISIBLE (-5948 5800);
FORCEADD TAP..1
R 2
(-5950 5700);
FORCEPROP 3 LASTPIN (-5900 5700) SIG_NAME M_F_CPU1_SA_DQS_DN<4>
J 0
(-5890 5710);
DISPLAY 0.659574 (-5890 5710);
PAINT MONO (-5890 5710);
DISPLAY INVISIBLE (-5890 5710);
FORCEPROP 1 LASTPIN (-5900 5700) BN 4
J 2
(-5888 5708);
DISPLAY 0.489362 (-5888 5708);
PAINT GREEN (-5888 5708);
FORCEPROP 2 LAST CDS_LIB mstr_standard
J 2
(-5950 5700);
DISPLAY 0.723404 (-5950 5700);
PAINT MONO (-5950 5700);
DISPLAY INVISIBLE (-5950 5700);
FORCEPROP 1 LAST BODY_TYPE PLUMBING
J 2
(-5950 5750);
DISPLAY 0.872340 (-5950 5750);
PAINT GREEN (-5950 5750);
DISPLAY INVISIBLE (-5950 5750);
FORCEPROP 1 LAST HDL_TAP TRUE
J 2
(-6275 5575);
DISPLAY 0.872340 (-6275 5575);
DISPLAY INVISIBLE (-6275 5575);
FORCEPROP 1 LAST PATH I254
J 2
(-5948 5700);
DISPLAY 0.872340 (-5948 5700);
PAINT GREEN (-5948 5700);
DISPLAY INVISIBLE (-5948 5700);
FORCEADD TAP..1
R 2
(-5750 5550);
FORCEPROP 3 LASTPIN (-5700 5550) SIG_NAME M_F_CPU1_SA_DQS_DP<6>
J 0
(-5690 5560);
DISPLAY 0.659574 (-5690 5560);
PAINT MONO (-5690 5560);
DISPLAY INVISIBLE (-5690 5560);
FORCEPROP 1 LASTPIN (-5700 5550) BN 6
J 2
(-5688 5558);
DISPLAY 0.489362 (-5688 5558);
PAINT GREEN (-5688 5558);
FORCEPROP 2 LAST CDS_LIB mstr_standard
J 2
(-5750 5550);
DISPLAY 0.723404 (-5750 5550);
PAINT MONO (-5750 5550);
DISPLAY INVISIBLE (-5750 5550);
FORCEPROP 1 LAST BODY_TYPE PLUMBING
J 2
(-5750 5600);
DISPLAY 0.872340 (-5750 5600);
PAINT GREEN (-5750 5600);
DISPLAY INVISIBLE (-5750 5600);
FORCEPROP 1 LAST HDL_TAP TRUE
J 2
(-6075 5425);
DISPLAY 0.872340 (-6075 5425);
DISPLAY INVISIBLE (-6075 5425);
FORCEPROP 1 LAST PATH I255
J 2
(-5748 5550);
DISPLAY 0.872340 (-5748 5550);
PAINT GREEN (-5748 5550);
DISPLAY INVISIBLE (-5748 5550);
FORCEADD TAP..1
R 2
(-5750 5450);
FORCEPROP 3 LASTPIN (-5700 5450) SIG_NAME M_F_CPU1_SA_DQS_DP<7>
J 0
(-5690 5460);
DISPLAY 0.659574 (-5690 5460);
PAINT MONO (-5690 5460);
DISPLAY INVISIBLE (-5690 5460);
FORCEPROP 1 LASTPIN (-5700 5450) BN 7
J 2
(-5688 5458);
DISPLAY 0.489362 (-5688 5458);
PAINT GREEN (-5688 5458);
FORCEPROP 2 LAST CDS_LIB mstr_standard
J 2
(-5750 5450);
DISPLAY 0.723404 (-5750 5450);
PAINT MONO (-5750 5450);
DISPLAY INVISIBLE (-5750 5450);
FORCEPROP 1 LAST BODY_TYPE PLUMBING
J 2
(-5750 5500);
DISPLAY 0.872340 (-5750 5500);
PAINT GREEN (-5750 5500);
DISPLAY INVISIBLE (-5750 5500);
FORCEPROP 1 LAST HDL_TAP TRUE
J 2
(-6075 5325);
DISPLAY 0.872340 (-6075 5325);
DISPLAY INVISIBLE (-6075 5325);
FORCEPROP 1 LAST PATH I256
J 2
(-5748 5450);
DISPLAY 0.872340 (-5748 5450);
PAINT GREEN (-5748 5450);
DISPLAY INVISIBLE (-5748 5450);
FORCEADD TAP..1
R 2
(-5750 5250);
FORCEPROP 3 LASTPIN (-5700 5250) SIG_NAME M_F_CPU1_SA_DQS_DP<9>
J 0
(-5690 5260);
DISPLAY 0.659574 (-5690 5260);
PAINT MONO (-5690 5260);
DISPLAY INVISIBLE (-5690 5260);
FORCEPROP 1 LASTPIN (-5700 5250) BN 9
J 2
(-5688 5258);
DISPLAY 0.489362 (-5688 5258);
PAINT GREEN (-5688 5258);
FORCEPROP 2 LAST CDS_LIB mstr_standard
J 2
(-5750 5250);
DISPLAY 0.723404 (-5750 5250);
PAINT MONO (-5750 5250);
DISPLAY INVISIBLE (-5750 5250);
FORCEPROP 1 LAST BODY_TYPE PLUMBING
J 2
(-5750 5300);
DISPLAY 0.872340 (-5750 5300);
PAINT GREEN (-5750 5300);
DISPLAY INVISIBLE (-5750 5300);
FORCEPROP 1 LAST HDL_TAP TRUE
J 2
(-6075 5125);
DISPLAY 0.872340 (-6075 5125);
DISPLAY INVISIBLE (-6075 5125);
FORCEPROP 1 LAST PATH I257
J 2
(-5748 5250);
DISPLAY 0.872340 (-5748 5250);
PAINT GREEN (-5748 5250);
DISPLAY INVISIBLE (-5748 5250);
FORCEADD TAP..1
R 2
(-5750 5350);
FORCEPROP 3 LASTPIN (-5700 5350) SIG_NAME M_F_CPU1_SA_DQS_DP<8>
J 0
(-5690 5360);
DISPLAY 0.659574 (-5690 5360);
PAINT MONO (-5690 5360);
DISPLAY INVISIBLE (-5690 5360);
FORCEPROP 1 LASTPIN (-5700 5350) BN 8
J 2
(-5688 5358);
DISPLAY 0.489362 (-5688 5358);
PAINT GREEN (-5688 5358);
FORCEPROP 2 LAST CDS_LIB mstr_standard
J 2
(-5750 5350);
DISPLAY 0.723404 (-5750 5350);
PAINT MONO (-5750 5350);
DISPLAY INVISIBLE (-5750 5350);
FORCEPROP 1 LAST BODY_TYPE PLUMBING
J 2
(-5750 5400);
DISPLAY 0.872340 (-5750 5400);
PAINT GREEN (-5750 5400);
DISPLAY INVISIBLE (-5750 5400);
FORCEPROP 1 LAST HDL_TAP TRUE
J 2
(-6075 5225);
DISPLAY 0.872340 (-6075 5225);
DISPLAY INVISIBLE (-6075 5225);
FORCEPROP 1 LAST PATH I258
J 2
(-5748 5350);
DISPLAY 0.872340 (-5748 5350);
PAINT GREEN (-5748 5350);
DISPLAY INVISIBLE (-5748 5350);
FORCEADD TAP..1
R 2
(-5950 5600);
FORCEPROP 3 LASTPIN (-5900 5600) SIG_NAME M_F_CPU1_SA_DQS_DN<5>
J 0
(-5890 5610);
DISPLAY 0.659574 (-5890 5610);
PAINT MONO (-5890 5610);
DISPLAY INVISIBLE (-5890 5610);
FORCEPROP 1 LASTPIN (-5900 5600) BN 5
J 2
(-5888 5608);
DISPLAY 0.489362 (-5888 5608);
PAINT GREEN (-5888 5608);
FORCEPROP 2 LAST CDS_LIB mstr_standard
J 2
(-5950 5600);
DISPLAY 0.723404 (-5950 5600);
PAINT MONO (-5950 5600);
DISPLAY INVISIBLE (-5950 5600);
FORCEPROP 1 LAST BODY_TYPE PLUMBING
J 2
(-5950 5650);
DISPLAY 0.872340 (-5950 5650);
PAINT GREEN (-5950 5650);
DISPLAY INVISIBLE (-5950 5650);
FORCEPROP 1 LAST HDL_TAP TRUE
J 2
(-6275 5475);
DISPLAY 0.872340 (-6275 5475);
DISPLAY INVISIBLE (-6275 5475);
FORCEPROP 1 LAST PATH I259
J 2
(-5948 5600);
DISPLAY 0.872340 (-5948 5600);
PAINT GREEN (-5948 5600);
DISPLAY INVISIBLE (-5948 5600);
FORCEADD TAP..1
R 2
(-5950 5500);
FORCEPROP 3 LASTPIN (-5900 5500) SIG_NAME M_F_CPU1_SA_DQS_DN<6>
J 0
(-5890 5510);
DISPLAY 0.659574 (-5890 5510);
PAINT MONO (-5890 5510);
DISPLAY INVISIBLE (-5890 5510);
FORCEPROP 1 LASTPIN (-5900 5500) BN 6
J 2
(-5888 5508);
DISPLAY 0.489362 (-5888 5508);
PAINT GREEN (-5888 5508);
FORCEPROP 2 LAST CDS_LIB mstr_standard
J 2
(-5950 5500);
DISPLAY 0.723404 (-5950 5500);
PAINT MONO (-5950 5500);
DISPLAY INVISIBLE (-5950 5500);
FORCEPROP 1 LAST BODY_TYPE PLUMBING
J 2
(-5950 5550);
DISPLAY 0.872340 (-5950 5550);
PAINT GREEN (-5950 5550);
DISPLAY INVISIBLE (-5950 5550);
FORCEPROP 1 LAST HDL_TAP TRUE
J 2
(-6275 5375);
DISPLAY 0.872340 (-6275 5375);
DISPLAY INVISIBLE (-6275 5375);
FORCEPROP 1 LAST PATH I260
J 2
(-5948 5500);
DISPLAY 0.872340 (-5948 5500);
PAINT GREEN (-5948 5500);
DISPLAY INVISIBLE (-5948 5500);
FORCEADD TAP..1
R 2
(-5950 5400);
FORCEPROP 3 LASTPIN (-5900 5400) SIG_NAME M_F_CPU1_SA_DQS_DN<7>
J 0
(-5890 5410);
DISPLAY 0.659574 (-5890 5410);
PAINT MONO (-5890 5410);
DISPLAY INVISIBLE (-5890 5410);
FORCEPROP 1 LASTPIN (-5900 5400) BN 7
J 2
(-5888 5408);
DISPLAY 0.489362 (-5888 5408);
PAINT GREEN (-5888 5408);
FORCEPROP 2 LAST CDS_LIB mstr_standard
J 2
(-5950 5400);
DISPLAY 0.723404 (-5950 5400);
PAINT MONO (-5950 5400);
DISPLAY INVISIBLE (-5950 5400);
FORCEPROP 1 LAST BODY_TYPE PLUMBING
J 2
(-5950 5450);
DISPLAY 0.872340 (-5950 5450);
PAINT GREEN (-5950 5450);
DISPLAY INVISIBLE (-5950 5450);
FORCEPROP 1 LAST HDL_TAP TRUE
J 2
(-6275 5275);
DISPLAY 0.872340 (-6275 5275);
DISPLAY INVISIBLE (-6275 5275);
FORCEPROP 1 LAST PATH I261
J 2
(-5948 5400);
DISPLAY 0.872340 (-5948 5400);
PAINT GREEN (-5948 5400);
DISPLAY INVISIBLE (-5948 5400);
FORCEADD TAP..1
R 2
(-5950 5300);
FORCEPROP 3 LASTPIN (-5900 5300) SIG_NAME M_F_CPU1_SA_DQS_DN<8>
J 0
(-5890 5310);
DISPLAY 0.659574 (-5890 5310);
PAINT MONO (-5890 5310);
DISPLAY INVISIBLE (-5890 5310);
FORCEPROP 1 LASTPIN (-5900 5300) BN 8
J 2
(-5888 5308);
DISPLAY 0.489362 (-5888 5308);
PAINT GREEN (-5888 5308);
FORCEPROP 2 LAST CDS_LIB mstr_standard
J 2
(-5950 5300);
DISPLAY 0.723404 (-5950 5300);
PAINT MONO (-5950 5300);
DISPLAY INVISIBLE (-5950 5300);
FORCEPROP 1 LAST BODY_TYPE PLUMBING
J 2
(-5950 5350);
DISPLAY 0.872340 (-5950 5350);
PAINT GREEN (-5950 5350);
DISPLAY INVISIBLE (-5950 5350);
FORCEPROP 1 LAST HDL_TAP TRUE
J 2
(-6275 5175);
DISPLAY 0.872340 (-6275 5175);
DISPLAY INVISIBLE (-6275 5175);
FORCEPROP 1 LAST PATH I262
J 2
(-5948 5300);
DISPLAY 0.872340 (-5948 5300);
PAINT GREEN (-5948 5300);
DISPLAY INVISIBLE (-5948 5300);
FORCEADD TAP..1
R 2
(-5950 5200);
FORCEPROP 3 LASTPIN (-5900 5200) SIG_NAME M_F_CPU1_SA_DQS_DN<9>
J 0
(-5890 5210);
DISPLAY 0.659574 (-5890 5210);
PAINT MONO (-5890 5210);
DISPLAY INVISIBLE (-5890 5210);
FORCEPROP 1 LASTPIN (-5900 5200) BN 9
J 2
(-5888 5208);
DISPLAY 0.489362 (-5888 5208);
PAINT GREEN (-5888 5208);
FORCEPROP 2 LAST CDS_LIB mstr_standard
J 2
(-5950 5200);
DISPLAY 0.723404 (-5950 5200);
PAINT MONO (-5950 5200);
DISPLAY INVISIBLE (-5950 5200);
FORCEPROP 1 LAST BODY_TYPE PLUMBING
J 2
(-5950 5250);
DISPLAY 0.872340 (-5950 5250);
PAINT GREEN (-5950 5250);
DISPLAY INVISIBLE (-5950 5250);
FORCEPROP 1 LAST HDL_TAP TRUE
J 2
(-6275 5075);
DISPLAY 0.872340 (-6275 5075);
DISPLAY INVISIBLE (-6275 5075);
FORCEPROP 1 LAST PATH I263
J 2
(-5948 5200);
DISPLAY 0.872340 (-5948 5200);
PAINT GREEN (-5948 5200);
DISPLAY INVISIBLE (-5948 5200);
FORCEADD TAP..1
R 2
(-5750 5000);
FORCEPROP 3 LASTPIN (-5700 5000) SIG_NAME M_F_CPU1_SB_DQS_DP<1>
J 0
(-5690 5010);
DISPLAY 0.659574 (-5690 5010);
PAINT MONO (-5690 5010);
DISPLAY INVISIBLE (-5690 5010);
FORCEPROP 1 LASTPIN (-5700 5000) BN 1
J 2
(-5688 5008);
DISPLAY 0.489362 (-5688 5008);
PAINT GREEN (-5688 5008);
FORCEPROP 2 LAST CDS_LIB mstr_standard
J 2
(-5750 5000);
DISPLAY 0.723404 (-5750 5000);
PAINT MONO (-5750 5000);
DISPLAY INVISIBLE (-5750 5000);
FORCEPROP 1 LAST BODY_TYPE PLUMBING
J 2
(-5750 5050);
DISPLAY 0.872340 (-5750 5050);
PAINT GREEN (-5750 5050);
DISPLAY INVISIBLE (-5750 5050);
FORCEPROP 1 LAST HDL_TAP TRUE
J 2
(-6075 4875);
DISPLAY 0.872340 (-6075 4875);
DISPLAY INVISIBLE (-6075 4875);
FORCEPROP 1 LAST PATH I264
J 2
(-5748 5000);
DISPLAY 0.872340 (-5748 5000);
PAINT GREEN (-5748 5000);
DISPLAY INVISIBLE (-5748 5000);
FORCEADD TAP..1
R 2
(-5750 5100);
FORCEPROP 3 LASTPIN (-5700 5100) SIG_NAME M_F_CPU1_SB_DQS_DP<0>
J 0
(-5690 5110);
DISPLAY 0.659574 (-5690 5110);
PAINT MONO (-5690 5110);
DISPLAY INVISIBLE (-5690 5110);
FORCEPROP 1 LASTPIN (-5700 5100) BN 0
J 2
(-5688 5108);
DISPLAY 0.489362 (-5688 5108);
PAINT GREEN (-5688 5108);
FORCEPROP 2 LAST CDS_LIB mstr_standard
J 2
(-5750 5100);
DISPLAY 0.723404 (-5750 5100);
PAINT MONO (-5750 5100);
DISPLAY INVISIBLE (-5750 5100);
FORCEPROP 1 LAST BODY_TYPE PLUMBING
J 2
(-5750 5150);
DISPLAY 0.872340 (-5750 5150);
PAINT GREEN (-5750 5150);
DISPLAY INVISIBLE (-5750 5150);
FORCEPROP 1 LAST HDL_TAP TRUE
J 2
(-6075 4975);
DISPLAY 0.872340 (-6075 4975);
DISPLAY INVISIBLE (-6075 4975);
FORCEPROP 1 LAST PATH I265
J 2
(-5748 5100);
DISPLAY 0.872340 (-5748 5100);
PAINT GREEN (-5748 5100);
DISPLAY INVISIBLE (-5748 5100);
FORCEADD TAP..1
R 2
(-5750 4900);
FORCEPROP 3 LASTPIN (-5700 4900) SIG_NAME M_F_CPU1_SB_DQS_DP<2>
J 0
(-5690 4910);
DISPLAY 0.659574 (-5690 4910);
PAINT MONO (-5690 4910);
DISPLAY INVISIBLE (-5690 4910);
FORCEPROP 1 LASTPIN (-5700 4900) BN 2
J 2
(-5688 4908);
DISPLAY 0.489362 (-5688 4908);
PAINT GREEN (-5688 4908);
FORCEPROP 2 LAST CDS_LIB mstr_standard
J 2
(-5750 4900);
DISPLAY 0.723404 (-5750 4900);
PAINT MONO (-5750 4900);
DISPLAY INVISIBLE (-5750 4900);
FORCEPROP 1 LAST BODY_TYPE PLUMBING
J 2
(-5750 4950);
DISPLAY 0.872340 (-5750 4950);
PAINT GREEN (-5750 4950);
DISPLAY INVISIBLE (-5750 4950);
FORCEPROP 1 LAST HDL_TAP TRUE
J 2
(-6075 4775);
DISPLAY 0.872340 (-6075 4775);
DISPLAY INVISIBLE (-6075 4775);
FORCEPROP 1 LAST PATH I266
J 2
(-5748 4900);
DISPLAY 0.872340 (-5748 4900);
PAINT GREEN (-5748 4900);
DISPLAY INVISIBLE (-5748 4900);
FORCEADD TAP..1
R 2
(-5750 4800);
FORCEPROP 3 LASTPIN (-5700 4800) SIG_NAME M_F_CPU1_SB_DQS_DP<3>
J 0
(-5690 4810);
DISPLAY 0.659574 (-5690 4810);
PAINT MONO (-5690 4810);
DISPLAY INVISIBLE (-5690 4810);
FORCEPROP 1 LASTPIN (-5700 4800) BN 3
J 2
(-5688 4808);
DISPLAY 0.489362 (-5688 4808);
PAINT GREEN (-5688 4808);
FORCEPROP 2 LAST CDS_LIB mstr_standard
J 2
(-5750 4800);
DISPLAY 0.723404 (-5750 4800);
PAINT MONO (-5750 4800);
DISPLAY INVISIBLE (-5750 4800);
FORCEPROP 1 LAST BODY_TYPE PLUMBING
J 2
(-5750 4850);
DISPLAY 0.872340 (-5750 4850);
PAINT GREEN (-5750 4850);
DISPLAY INVISIBLE (-5750 4850);
FORCEPROP 1 LAST HDL_TAP TRUE
J 2
(-6075 4675);
DISPLAY 0.872340 (-6075 4675);
DISPLAY INVISIBLE (-6075 4675);
FORCEPROP 1 LAST PATH I267
J 2
(-5748 4800);
DISPLAY 0.872340 (-5748 4800);
PAINT GREEN (-5748 4800);
DISPLAY INVISIBLE (-5748 4800);
FORCEADD TAP..1
R 2
(-5750 4700);
FORCEPROP 3 LASTPIN (-5700 4700) SIG_NAME M_F_CPU1_SB_DQS_DP<4>
J 0
(-5690 4710);
DISPLAY 0.659574 (-5690 4710);
PAINT MONO (-5690 4710);
DISPLAY INVISIBLE (-5690 4710);
FORCEPROP 1 LASTPIN (-5700 4700) BN 4
J 2
(-5688 4708);
DISPLAY 0.489362 (-5688 4708);
PAINT GREEN (-5688 4708);
FORCEPROP 2 LAST CDS_LIB mstr_standard
J 2
(-5750 4700);
DISPLAY 0.723404 (-5750 4700);
PAINT MONO (-5750 4700);
DISPLAY INVISIBLE (-5750 4700);
FORCEPROP 1 LAST BODY_TYPE PLUMBING
J 2
(-5750 4750);
DISPLAY 0.872340 (-5750 4750);
PAINT GREEN (-5750 4750);
DISPLAY INVISIBLE (-5750 4750);
FORCEPROP 1 LAST HDL_TAP TRUE
J 2
(-6075 4575);
DISPLAY 0.872340 (-6075 4575);
DISPLAY INVISIBLE (-6075 4575);
FORCEPROP 1 LAST PATH I268
J 2
(-5748 4700);
DISPLAY 0.872340 (-5748 4700);
PAINT GREEN (-5748 4700);
DISPLAY INVISIBLE (-5748 4700);
FORCEADD TAP..1
R 2
(-5950 5050);
FORCEPROP 3 LASTPIN (-5900 5050) SIG_NAME M_F_CPU1_SB_DQS_DN<0>
J 0
(-5890 5060);
DISPLAY 0.659574 (-5890 5060);
PAINT MONO (-5890 5060);
DISPLAY INVISIBLE (-5890 5060);
FORCEPROP 1 LASTPIN (-5900 5050) BN 0
J 2
(-5888 5058);
DISPLAY 0.489362 (-5888 5058);
PAINT GREEN (-5888 5058);
FORCEPROP 2 LAST CDS_LIB mstr_standard
J 2
(-5950 5050);
DISPLAY 0.723404 (-5950 5050);
PAINT MONO (-5950 5050);
DISPLAY INVISIBLE (-5950 5050);
FORCEPROP 1 LAST BODY_TYPE PLUMBING
J 2
(-5950 5100);
DISPLAY 0.872340 (-5950 5100);
PAINT GREEN (-5950 5100);
DISPLAY INVISIBLE (-5950 5100);
FORCEPROP 1 LAST HDL_TAP TRUE
J 2
(-6275 4925);
DISPLAY 0.872340 (-6275 4925);
DISPLAY INVISIBLE (-6275 4925);
FORCEPROP 1 LAST PATH I269
J 2
(-5948 5050);
DISPLAY 0.872340 (-5948 5050);
PAINT GREEN (-5948 5050);
DISPLAY INVISIBLE (-5948 5050);
FORCEADD TAP..1
R 2
(-5950 4950);
FORCEPROP 3 LASTPIN (-5900 4950) SIG_NAME M_F_CPU1_SB_DQS_DN<1>
J 0
(-5890 4960);
DISPLAY 0.659574 (-5890 4960);
PAINT MONO (-5890 4960);
DISPLAY INVISIBLE (-5890 4960);
FORCEPROP 1 LASTPIN (-5900 4950) BN 1
J 2
(-5888 4958);
DISPLAY 0.489362 (-5888 4958);
PAINT GREEN (-5888 4958);
FORCEPROP 2 LAST CDS_LIB mstr_standard
J 2
(-5950 4950);
DISPLAY 0.723404 (-5950 4950);
PAINT MONO (-5950 4950);
DISPLAY INVISIBLE (-5950 4950);
FORCEPROP 1 LAST BODY_TYPE PLUMBING
J 2
(-5950 5000);
DISPLAY 0.872340 (-5950 5000);
PAINT GREEN (-5950 5000);
DISPLAY INVISIBLE (-5950 5000);
FORCEPROP 1 LAST HDL_TAP TRUE
J 2
(-6275 4825);
DISPLAY 0.872340 (-6275 4825);
DISPLAY INVISIBLE (-6275 4825);
FORCEPROP 1 LAST PATH I270
J 2
(-5948 4950);
DISPLAY 0.872340 (-5948 4950);
PAINT GREEN (-5948 4950);
DISPLAY INVISIBLE (-5948 4950);
FORCEADD TAP..1
R 2
(-5950 4850);
FORCEPROP 3 LASTPIN (-5900 4850) SIG_NAME M_F_CPU1_SB_DQS_DN<2>
J 0
(-5890 4860);
DISPLAY 0.659574 (-5890 4860);
PAINT MONO (-5890 4860);
DISPLAY INVISIBLE (-5890 4860);
FORCEPROP 1 LASTPIN (-5900 4850) BN 2
J 2
(-5888 4858);
DISPLAY 0.489362 (-5888 4858);
PAINT GREEN (-5888 4858);
FORCEPROP 2 LAST CDS_LIB mstr_standard
J 2
(-5950 4850);
DISPLAY 0.723404 (-5950 4850);
PAINT MONO (-5950 4850);
DISPLAY INVISIBLE (-5950 4850);
FORCEPROP 1 LAST BODY_TYPE PLUMBING
J 2
(-5950 4900);
DISPLAY 0.872340 (-5950 4900);
PAINT GREEN (-5950 4900);
DISPLAY INVISIBLE (-5950 4900);
FORCEPROP 1 LAST HDL_TAP TRUE
J 2
(-6275 4725);
DISPLAY 0.872340 (-6275 4725);
DISPLAY INVISIBLE (-6275 4725);
FORCEPROP 1 LAST PATH I271
J 2
(-5948 4850);
DISPLAY 0.872340 (-5948 4850);
PAINT GREEN (-5948 4850);
DISPLAY INVISIBLE (-5948 4850);
FORCEADD TAP..1
R 2
(-5950 4750);
FORCEPROP 3 LASTPIN (-5900 4750) SIG_NAME M_F_CPU1_SB_DQS_DN<3>
J 0
(-5890 4760);
DISPLAY 0.659574 (-5890 4760);
PAINT MONO (-5890 4760);
DISPLAY INVISIBLE (-5890 4760);
FORCEPROP 1 LASTPIN (-5900 4750) BN 3
J 2
(-5888 4758);
DISPLAY 0.489362 (-5888 4758);
PAINT GREEN (-5888 4758);
FORCEPROP 2 LAST CDS_LIB mstr_standard
J 2
(-5950 4750);
DISPLAY 0.723404 (-5950 4750);
PAINT MONO (-5950 4750);
DISPLAY INVISIBLE (-5950 4750);
FORCEPROP 1 LAST BODY_TYPE PLUMBING
J 2
(-5950 4800);
DISPLAY 0.872340 (-5950 4800);
PAINT GREEN (-5950 4800);
DISPLAY INVISIBLE (-5950 4800);
FORCEPROP 1 LAST HDL_TAP TRUE
J 2
(-6275 4625);
DISPLAY 0.872340 (-6275 4625);
DISPLAY INVISIBLE (-6275 4625);
FORCEPROP 1 LAST PATH I272
J 2
(-5948 4750);
DISPLAY 0.872340 (-5948 4750);
PAINT GREEN (-5948 4750);
DISPLAY INVISIBLE (-5948 4750);
FORCEADD TAP..1
R 2
(-5950 4650);
FORCEPROP 3 LASTPIN (-5900 4650) SIG_NAME M_F_CPU1_SB_DQS_DN<4>
J 0
(-5890 4660);
DISPLAY 0.659574 (-5890 4660);
PAINT MONO (-5890 4660);
DISPLAY INVISIBLE (-5890 4660);
FORCEPROP 1 LASTPIN (-5900 4650) BN 4
J 2
(-5888 4658);
DISPLAY 0.489362 (-5888 4658);
PAINT GREEN (-5888 4658);
FORCEPROP 2 LAST CDS_LIB mstr_standard
J 2
(-5950 4650);
DISPLAY 0.723404 (-5950 4650);
PAINT MONO (-5950 4650);
DISPLAY INVISIBLE (-5950 4650);
FORCEPROP 1 LAST BODY_TYPE PLUMBING
J 2
(-5950 4700);
DISPLAY 0.872340 (-5950 4700);
PAINT GREEN (-5950 4700);
DISPLAY INVISIBLE (-5950 4700);
FORCEPROP 1 LAST HDL_TAP TRUE
J 2
(-6275 4525);
DISPLAY 0.872340 (-6275 4525);
DISPLAY INVISIBLE (-6275 4525);
FORCEPROP 1 LAST PATH I273
J 2
(-5948 4650);
DISPLAY 0.872340 (-5948 4650);
PAINT GREEN (-5948 4650);
DISPLAY INVISIBLE (-5948 4650);
FORCEADD TAP..1
R 2
(-5750 4500);
FORCEPROP 3 LASTPIN (-5700 4500) SIG_NAME M_F_CPU1_SB_DQS_DP<6>
J 0
(-5690 4510);
DISPLAY 0.659574 (-5690 4510);
PAINT MONO (-5690 4510);
DISPLAY INVISIBLE (-5690 4510);
FORCEPROP 1 LASTPIN (-5700 4500) BN 6
J 2
(-5688 4508);
DISPLAY 0.489362 (-5688 4508);
PAINT GREEN (-5688 4508);
FORCEPROP 2 LAST CDS_LIB mstr_standard
J 2
(-5750 4500);
DISPLAY 0.723404 (-5750 4500);
PAINT MONO (-5750 4500);
DISPLAY INVISIBLE (-5750 4500);
FORCEPROP 1 LAST BODY_TYPE PLUMBING
J 2
(-5750 4550);
DISPLAY 0.872340 (-5750 4550);
PAINT GREEN (-5750 4550);
DISPLAY INVISIBLE (-5750 4550);
FORCEPROP 1 LAST HDL_TAP TRUE
J 2
(-6075 4375);
DISPLAY 0.872340 (-6075 4375);
DISPLAY INVISIBLE (-6075 4375);
FORCEPROP 1 LAST PATH I274
J 2
(-5748 4500);
DISPLAY 0.872340 (-5748 4500);
PAINT GREEN (-5748 4500);
DISPLAY INVISIBLE (-5748 4500);
FORCEADD TAP..1
R 2
(-5750 4600);
FORCEPROP 3 LASTPIN (-5700 4600) SIG_NAME M_F_CPU1_SB_DQS_DP<5>
J 0
(-5690 4610);
DISPLAY 0.659574 (-5690 4610);
PAINT MONO (-5690 4610);
DISPLAY INVISIBLE (-5690 4610);
FORCEPROP 1 LASTPIN (-5700 4600) BN 5
J 2
(-5688 4608);
DISPLAY 0.489362 (-5688 4608);
PAINT GREEN (-5688 4608);
FORCEPROP 2 LAST CDS_LIB mstr_standard
J 2
(-5750 4600);
DISPLAY 0.723404 (-5750 4600);
PAINT MONO (-5750 4600);
DISPLAY INVISIBLE (-5750 4600);
FORCEPROP 1 LAST BODY_TYPE PLUMBING
J 2
(-5750 4650);
DISPLAY 0.872340 (-5750 4650);
PAINT GREEN (-5750 4650);
DISPLAY INVISIBLE (-5750 4650);
FORCEPROP 1 LAST HDL_TAP TRUE
J 2
(-6075 4475);
DISPLAY 0.872340 (-6075 4475);
DISPLAY INVISIBLE (-6075 4475);
FORCEPROP 1 LAST PATH I275
J 2
(-5748 4600);
DISPLAY 0.872340 (-5748 4600);
PAINT GREEN (-5748 4600);
DISPLAY INVISIBLE (-5748 4600);
FORCEADD TAP..1
R 2
(-5750 4400);
FORCEPROP 3 LASTPIN (-5700 4400) SIG_NAME M_F_CPU1_SB_DQS_DP<7>
J 0
(-5690 4410);
DISPLAY 0.659574 (-5690 4410);
PAINT MONO (-5690 4410);
DISPLAY INVISIBLE (-5690 4410);
FORCEPROP 1 LASTPIN (-5700 4400) BN 7
J 2
(-5688 4408);
DISPLAY 0.489362 (-5688 4408);
PAINT GREEN (-5688 4408);
FORCEPROP 2 LAST CDS_LIB mstr_standard
J 2
(-5750 4400);
DISPLAY 0.723404 (-5750 4400);
PAINT MONO (-5750 4400);
DISPLAY INVISIBLE (-5750 4400);
FORCEPROP 1 LAST BODY_TYPE PLUMBING
J 2
(-5750 4450);
DISPLAY 0.872340 (-5750 4450);
PAINT GREEN (-5750 4450);
DISPLAY INVISIBLE (-5750 4450);
FORCEPROP 1 LAST HDL_TAP TRUE
J 2
(-6075 4275);
DISPLAY 0.872340 (-6075 4275);
DISPLAY INVISIBLE (-6075 4275);
FORCEPROP 1 LAST PATH I276
J 2
(-5748 4400);
DISPLAY 0.872340 (-5748 4400);
PAINT GREEN (-5748 4400);
DISPLAY INVISIBLE (-5748 4400);
FORCEADD TAP..1
R 2
(-5750 4300);
FORCEPROP 3 LASTPIN (-5700 4300) SIG_NAME M_F_CPU1_SB_DQS_DP<8>
J 0
(-5690 4310);
DISPLAY 0.659574 (-5690 4310);
PAINT MONO (-5690 4310);
DISPLAY INVISIBLE (-5690 4310);
FORCEPROP 1 LASTPIN (-5700 4300) BN 8
J 2
(-5688 4308);
DISPLAY 0.489362 (-5688 4308);
PAINT GREEN (-5688 4308);
FORCEPROP 2 LAST CDS_LIB mstr_standard
J 2
(-5750 4300);
DISPLAY 0.723404 (-5750 4300);
PAINT MONO (-5750 4300);
DISPLAY INVISIBLE (-5750 4300);
FORCEPROP 1 LAST BODY_TYPE PLUMBING
J 2
(-5750 4350);
DISPLAY 0.872340 (-5750 4350);
PAINT GREEN (-5750 4350);
DISPLAY INVISIBLE (-5750 4350);
FORCEPROP 1 LAST HDL_TAP TRUE
J 2
(-6075 4175);
DISPLAY 0.872340 (-6075 4175);
DISPLAY INVISIBLE (-6075 4175);
FORCEPROP 1 LAST PATH I277
J 2
(-5748 4300);
DISPLAY 0.872340 (-5748 4300);
PAINT GREEN (-5748 4300);
DISPLAY INVISIBLE (-5748 4300);
FORCEADD TAP..1
R 2
(-5750 4200);
FORCEPROP 3 LASTPIN (-5700 4200) SIG_NAME M_F_CPU1_SB_DQS_DP<9>
J 0
(-5690 4210);
DISPLAY 0.659574 (-5690 4210);
PAINT MONO (-5690 4210);
DISPLAY INVISIBLE (-5690 4210);
FORCEPROP 1 LASTPIN (-5700 4200) BN 9
J 2
(-5688 4208);
DISPLAY 0.489362 (-5688 4208);
PAINT GREEN (-5688 4208);
FORCEPROP 2 LAST CDS_LIB mstr_standard
J 2
(-5750 4200);
DISPLAY 0.723404 (-5750 4200);
PAINT MONO (-5750 4200);
DISPLAY INVISIBLE (-5750 4200);
FORCEPROP 1 LAST BODY_TYPE PLUMBING
J 2
(-5750 4250);
DISPLAY 0.872340 (-5750 4250);
PAINT GREEN (-5750 4250);
DISPLAY INVISIBLE (-5750 4250);
FORCEPROP 1 LAST HDL_TAP TRUE
J 2
(-6075 4075);
DISPLAY 0.872340 (-6075 4075);
DISPLAY INVISIBLE (-6075 4075);
FORCEPROP 1 LAST PATH I278
J 2
(-5748 4200);
DISPLAY 0.872340 (-5748 4200);
PAINT GREEN (-5748 4200);
DISPLAY INVISIBLE (-5748 4200);
FORCEADD TAP..1
R 2
(-5950 4550);
FORCEPROP 3 LASTPIN (-5900 4550) SIG_NAME M_F_CPU1_SB_DQS_DN<5>
J 0
(-5890 4560);
DISPLAY 0.659574 (-5890 4560);
PAINT MONO (-5890 4560);
DISPLAY INVISIBLE (-5890 4560);
FORCEPROP 1 LASTPIN (-5900 4550) BN 5
J 2
(-5888 4558);
DISPLAY 0.489362 (-5888 4558);
PAINT GREEN (-5888 4558);
FORCEPROP 2 LAST CDS_LIB mstr_standard
J 2
(-5950 4550);
DISPLAY 0.723404 (-5950 4550);
PAINT MONO (-5950 4550);
DISPLAY INVISIBLE (-5950 4550);
FORCEPROP 1 LAST BODY_TYPE PLUMBING
J 2
(-5950 4600);
DISPLAY 0.872340 (-5950 4600);
PAINT GREEN (-5950 4600);
DISPLAY INVISIBLE (-5950 4600);
FORCEPROP 1 LAST HDL_TAP TRUE
J 2
(-6275 4425);
DISPLAY 0.872340 (-6275 4425);
DISPLAY INVISIBLE (-6275 4425);
FORCEPROP 1 LAST PATH I279
J 2
(-5948 4550);
DISPLAY 0.872340 (-5948 4550);
PAINT GREEN (-5948 4550);
DISPLAY INVISIBLE (-5948 4550);
FORCEADD TAP..1
R 2
(-5950 4450);
FORCEPROP 3 LASTPIN (-5900 4450) SIG_NAME M_F_CPU1_SB_DQS_DN<6>
J 0
(-5890 4460);
DISPLAY 0.659574 (-5890 4460);
PAINT MONO (-5890 4460);
DISPLAY INVISIBLE (-5890 4460);
FORCEPROP 1 LASTPIN (-5900 4450) BN 6
J 2
(-5888 4458);
DISPLAY 0.489362 (-5888 4458);
PAINT GREEN (-5888 4458);
FORCEPROP 2 LAST CDS_LIB mstr_standard
J 2
(-5950 4450);
DISPLAY 0.723404 (-5950 4450);
PAINT MONO (-5950 4450);
DISPLAY INVISIBLE (-5950 4450);
FORCEPROP 1 LAST BODY_TYPE PLUMBING
J 2
(-5950 4500);
DISPLAY 0.872340 (-5950 4500);
PAINT GREEN (-5950 4500);
DISPLAY INVISIBLE (-5950 4500);
FORCEPROP 1 LAST HDL_TAP TRUE
J 2
(-6275 4325);
DISPLAY 0.872340 (-6275 4325);
DISPLAY INVISIBLE (-6275 4325);
FORCEPROP 1 LAST PATH I280
J 2
(-5948 4450);
DISPLAY 0.872340 (-5948 4450);
PAINT GREEN (-5948 4450);
DISPLAY INVISIBLE (-5948 4450);
FORCEADD TAP..1
R 2
(-5950 4350);
FORCEPROP 3 LASTPIN (-5900 4350) SIG_NAME M_F_CPU1_SB_DQS_DN<7>
J 0
(-5890 4360);
DISPLAY 0.659574 (-5890 4360);
PAINT MONO (-5890 4360);
DISPLAY INVISIBLE (-5890 4360);
FORCEPROP 1 LASTPIN (-5900 4350) BN 7
J 2
(-5888 4358);
DISPLAY 0.489362 (-5888 4358);
PAINT GREEN (-5888 4358);
FORCEPROP 2 LAST CDS_LIB mstr_standard
J 2
(-5950 4350);
DISPLAY 0.723404 (-5950 4350);
PAINT MONO (-5950 4350);
DISPLAY INVISIBLE (-5950 4350);
FORCEPROP 1 LAST BODY_TYPE PLUMBING
J 2
(-5950 4400);
DISPLAY 0.872340 (-5950 4400);
PAINT GREEN (-5950 4400);
DISPLAY INVISIBLE (-5950 4400);
FORCEPROP 1 LAST HDL_TAP TRUE
J 2
(-6275 4225);
DISPLAY 0.872340 (-6275 4225);
DISPLAY INVISIBLE (-6275 4225);
FORCEPROP 1 LAST PATH I281
J 2
(-5948 4350);
DISPLAY 0.872340 (-5948 4350);
PAINT GREEN (-5948 4350);
DISPLAY INVISIBLE (-5948 4350);
FORCEADD TAP..1
R 2
(-5950 4150);
FORCEPROP 3 LASTPIN (-5900 4150) SIG_NAME M_F_CPU1_SB_DQS_DN<9>
J 0
(-5890 4160);
DISPLAY 0.659574 (-5890 4160);
PAINT MONO (-5890 4160);
DISPLAY INVISIBLE (-5890 4160);
FORCEPROP 1 LASTPIN (-5900 4150) BN 9
J 2
(-5888 4158);
DISPLAY 0.489362 (-5888 4158);
PAINT GREEN (-5888 4158);
FORCEPROP 2 LAST CDS_LIB mstr_standard
J 2
(-5950 4150);
DISPLAY 0.723404 (-5950 4150);
PAINT MONO (-5950 4150);
DISPLAY INVISIBLE (-5950 4150);
FORCEPROP 1 LAST BODY_TYPE PLUMBING
J 2
(-5950 4200);
DISPLAY 0.872340 (-5950 4200);
PAINT GREEN (-5950 4200);
DISPLAY INVISIBLE (-5950 4200);
FORCEPROP 1 LAST HDL_TAP TRUE
J 2
(-6275 4025);
DISPLAY 0.872340 (-6275 4025);
DISPLAY INVISIBLE (-6275 4025);
FORCEPROP 1 LAST PATH I282
J 2
(-5948 4150);
DISPLAY 0.872340 (-5948 4150);
PAINT GREEN (-5948 4150);
DISPLAY INVISIBLE (-5948 4150);
FORCEADD TAP..1
R 2
(-5950 4250);
FORCEPROP 3 LASTPIN (-5900 4250) SIG_NAME M_F_CPU1_SB_DQS_DN<8>
J 0
(-5890 4260);
DISPLAY 0.659574 (-5890 4260);
PAINT MONO (-5890 4260);
DISPLAY INVISIBLE (-5890 4260);
FORCEPROP 1 LASTPIN (-5900 4250) BN 8
J 2
(-5888 4258);
DISPLAY 0.489362 (-5888 4258);
PAINT GREEN (-5888 4258);
FORCEPROP 2 LAST CDS_LIB mstr_standard
J 2
(-5950 4250);
DISPLAY 0.723404 (-5950 4250);
PAINT MONO (-5950 4250);
DISPLAY INVISIBLE (-5950 4250);
FORCEPROP 1 LAST BODY_TYPE PLUMBING
J 2
(-5950 4300);
DISPLAY 0.872340 (-5950 4300);
PAINT GREEN (-5950 4300);
DISPLAY INVISIBLE (-5950 4300);
FORCEPROP 1 LAST HDL_TAP TRUE
J 2
(-6275 4125);
DISPLAY 0.872340 (-6275 4125);
DISPLAY INVISIBLE (-6275 4125);
FORCEPROP 1 LAST PATH I283
J 2
(-5948 4250);
DISPLAY 0.872340 (-5948 4250);
PAINT GREEN (-5948 4250);
DISPLAY INVISIBLE (-5948 4250);
FORCEADD OFFPAGE..3
R 2
(-6650 6175);
FORCEPROP 2 LAST $XR0 103 
J 0
(-6930 6175);
DISPLAY 0.638298 (-6930 6175);
PAINT MONO (-6930 6175);
FORCEPROP 2 LAST CDS_LIB standard
J 0
(-6650 6175);
DISPLAY INVISIBLE (-6650 6175);
FORCEPROP 1 LAST OFFPAGE TRUE
J 2
(-6975 6050);
DISPLAY 0.872340 (-6975 6050);
PAINT GREEN (-6975 6050);
DISPLAY INVISIBLE (-6975 6050);
FORCEPROP 1 LAST COMMENT_BODY TRUE
J 2
(-6600 6075);
DISPLAY 0.872340 (-6600 6075);
PAINT GREEN (-6600 6075);
DISPLAY INVISIBLE (-6600 6075);
FORCEPROP 2 LAST PATH I284
J 0
(-6925 6225);
DISPLAY 1.021277 (-6925 6225);
DISPLAY INVISIBLE (-6925 6225);
FORCEADD OFFPAGE..3
R 2
(-6650 6125);
FORCEPROP 2 LAST $XR0 103 
J 0
(-6930 6125);
DISPLAY 0.638298 (-6930 6125);
PAINT MONO (-6930 6125);
FORCEPROP 2 LAST CDS_LIB standard
J 0
(-6650 6125);
DISPLAY INVISIBLE (-6650 6125);
FORCEPROP 1 LAST OFFPAGE TRUE
J 2
(-6975 6000);
DISPLAY 0.872340 (-6975 6000);
PAINT GREEN (-6975 6000);
DISPLAY INVISIBLE (-6975 6000);
FORCEPROP 1 LAST COMMENT_BODY TRUE
J 2
(-6600 6025);
DISPLAY 0.872340 (-6600 6025);
PAINT GREEN (-6600 6025);
DISPLAY INVISIBLE (-6600 6025);
FORCEPROP 2 LAST PATH I285
J 0
(-6925 6175);
DISPLAY 1.021277 (-6925 6175);
DISPLAY INVISIBLE (-6925 6175);
FORCEADD OFFPAGE..3
R 2
(-6650 5125);
FORCEPROP 2 LAST $XR0 103 
J 0
(-6930 5125);
DISPLAY 0.638298 (-6930 5125);
PAINT MONO (-6930 5125);
FORCEPROP 2 LAST CDS_LIB standard
J 0
(-6650 5125);
DISPLAY INVISIBLE (-6650 5125);
FORCEPROP 1 LAST OFFPAGE TRUE
J 2
(-6975 5000);
DISPLAY 0.872340 (-6975 5000);
PAINT GREEN (-6975 5000);
DISPLAY INVISIBLE (-6975 5000);
FORCEPROP 1 LAST COMMENT_BODY TRUE
J 2
(-6600 5025);
DISPLAY 0.872340 (-6600 5025);
PAINT GREEN (-6600 5025);
DISPLAY INVISIBLE (-6600 5025);
FORCEPROP 2 LAST PATH I286
J 0
(-6925 5175);
DISPLAY 1.021277 (-6925 5175);
DISPLAY INVISIBLE (-6925 5175);
FORCEADD OFFPAGE..3
R 2
(-6650 5075);
FORCEPROP 2 LAST $XR0 103 
J 0
(-6930 5075);
DISPLAY 0.638298 (-6930 5075);
PAINT MONO (-6930 5075);
FORCEPROP 2 LAST CDS_LIB standard
J 0
(-6650 5075);
DISPLAY INVISIBLE (-6650 5075);
FORCEPROP 1 LAST OFFPAGE TRUE
J 2
(-6975 4950);
DISPLAY 0.872340 (-6975 4950);
PAINT GREEN (-6975 4950);
DISPLAY INVISIBLE (-6975 4950);
FORCEPROP 1 LAST COMMENT_BODY TRUE
J 2
(-6600 4975);
DISPLAY 0.872340 (-6600 4975);
PAINT GREEN (-6600 4975);
DISPLAY INVISIBLE (-6600 4975);
FORCEPROP 2 LAST PATH I287
J 0
(-6925 5125);
DISPLAY 1.021277 (-6925 5125);
DISPLAY INVISIBLE (-6925 5125);
FORCEADD TAP..1
R 2
(-5950 3950);
FORCEPROP 3 LASTPIN (-5900 3950) SIG_NAME M_F_CPU1_SA_CA<1>
J 0
(-5890 3960);
DISPLAY 0.659574 (-5890 3960);
PAINT MONO (-5890 3960);
DISPLAY INVISIBLE (-5890 3960);
FORCEPROP 1 LASTPIN (-5900 3950) BN 1
J 2
(-5888 3958);
DISPLAY 0.489362 (-5888 3958);
PAINT GREEN (-5888 3958);
FORCEPROP 2 LAST CDS_LIB mstr_standard
J 0
(-5950 3950);
DISPLAY 0.723404 (-5950 3950);
PAINT MONO (-5950 3950);
DISPLAY INVISIBLE (-5950 3950);
FORCEPROP 1 LAST BODY_TYPE PLUMBING
J 2
(-5950 4000);
DISPLAY 0.872340 (-5950 4000);
PAINT GREEN (-5950 4000);
DISPLAY INVISIBLE (-5950 4000);
FORCEPROP 1 LAST HDL_TAP TRUE
J 2
(-6275 3825);
DISPLAY 0.872340 (-6275 3825);
DISPLAY INVISIBLE (-6275 3825);
FORCEPROP 1 LAST PATH I288
J 2
(-5948 3950);
DISPLAY 0.872340 (-5948 3950);
PAINT GREEN (-5948 3950);
DISPLAY INVISIBLE (-5948 3950);
FORCEADD TAP..1
R 2
(-5950 4000);
FORCEPROP 3 LASTPIN (-5900 4000) SIG_NAME M_F_CPU1_SA_CA<0>
J 0
(-5890 4010);
DISPLAY 0.659574 (-5890 4010);
PAINT MONO (-5890 4010);
DISPLAY INVISIBLE (-5890 4010);
FORCEPROP 1 LASTPIN (-5900 4000) BN 0
J 2
(-5888 4008);
DISPLAY 0.489362 (-5888 4008);
PAINT GREEN (-5888 4008);
FORCEPROP 2 LAST CDS_LIB mstr_standard
J 0
(-5950 4000);
DISPLAY 0.723404 (-5950 4000);
PAINT MONO (-5950 4000);
DISPLAY INVISIBLE (-5950 4000);
FORCEPROP 1 LAST BODY_TYPE PLUMBING
J 2
(-5950 4050);
DISPLAY 0.872340 (-5950 4050);
PAINT GREEN (-5950 4050);
DISPLAY INVISIBLE (-5950 4050);
FORCEPROP 1 LAST HDL_TAP TRUE
J 2
(-6275 3875);
DISPLAY 0.872340 (-6275 3875);
DISPLAY INVISIBLE (-6275 3875);
FORCEPROP 1 LAST PATH I289
J 2
(-5948 4000);
DISPLAY 0.872340 (-5948 4000);
PAINT GREEN (-5948 4000);
DISPLAY INVISIBLE (-5948 4000);
FORCEADD TAP..1
R 2
(-5950 3900);
FORCEPROP 3 LASTPIN (-5900 3900) SIG_NAME M_F_CPU1_SA_CA<2>
J 0
(-5890 3910);
DISPLAY 0.659574 (-5890 3910);
PAINT MONO (-5890 3910);
DISPLAY INVISIBLE (-5890 3910);
FORCEPROP 1 LASTPIN (-5900 3900) BN 2
J 2
(-5888 3908);
DISPLAY 0.489362 (-5888 3908);
PAINT GREEN (-5888 3908);
FORCEPROP 2 LAST CDS_LIB mstr_standard
J 0
(-5950 3900);
DISPLAY 0.723404 (-5950 3900);
PAINT MONO (-5950 3900);
DISPLAY INVISIBLE (-5950 3900);
FORCEPROP 1 LAST BODY_TYPE PLUMBING
J 2
(-5950 3950);
DISPLAY 0.872340 (-5950 3950);
PAINT GREEN (-5950 3950);
DISPLAY INVISIBLE (-5950 3950);
FORCEPROP 1 LAST HDL_TAP TRUE
J 2
(-6275 3775);
DISPLAY 0.872340 (-6275 3775);
DISPLAY INVISIBLE (-6275 3775);
FORCEPROP 1 LAST PATH I290
J 2
(-5948 3900);
DISPLAY 0.872340 (-5948 3900);
PAINT GREEN (-5948 3900);
DISPLAY INVISIBLE (-5948 3900);
FORCEADD TAP..1
R 2
(-5950 3850);
FORCEPROP 3 LASTPIN (-5900 3850) SIG_NAME M_F_CPU1_SA_CA<3>
J 0
(-5890 3860);
DISPLAY 0.659574 (-5890 3860);
PAINT MONO (-5890 3860);
DISPLAY INVISIBLE (-5890 3860);
FORCEPROP 1 LASTPIN (-5900 3850) BN 3
J 2
(-5888 3858);
DISPLAY 0.489362 (-5888 3858);
PAINT GREEN (-5888 3858);
FORCEPROP 2 LAST CDS_LIB mstr_standard
J 0
(-5950 3850);
DISPLAY 0.723404 (-5950 3850);
PAINT MONO (-5950 3850);
DISPLAY INVISIBLE (-5950 3850);
FORCEPROP 1 LAST BODY_TYPE PLUMBING
J 2
(-5950 3900);
DISPLAY 0.872340 (-5950 3900);
PAINT GREEN (-5950 3900);
DISPLAY INVISIBLE (-5950 3900);
FORCEPROP 1 LAST HDL_TAP TRUE
J 2
(-6275 3725);
DISPLAY 0.872340 (-6275 3725);
DISPLAY INVISIBLE (-6275 3725);
FORCEPROP 1 LAST PATH I291
J 2
(-5948 3850);
DISPLAY 0.872340 (-5948 3850);
PAINT GREEN (-5948 3850);
DISPLAY INVISIBLE (-5948 3850);
FORCEADD TAP..1
R 2
(-5950 3800);
FORCEPROP 3 LASTPIN (-5900 3800) SIG_NAME M_F_CPU1_SA_CA<4>
J 0
(-5890 3810);
DISPLAY 0.659574 (-5890 3810);
PAINT MONO (-5890 3810);
DISPLAY INVISIBLE (-5890 3810);
FORCEPROP 1 LASTPIN (-5900 3800) BN 4
J 2
(-5888 3808);
DISPLAY 0.489362 (-5888 3808);
PAINT GREEN (-5888 3808);
FORCEPROP 2 LAST CDS_LIB mstr_standard
J 0
(-5950 3800);
DISPLAY 0.723404 (-5950 3800);
PAINT MONO (-5950 3800);
DISPLAY INVISIBLE (-5950 3800);
FORCEPROP 1 LAST BODY_TYPE PLUMBING
J 2
(-5950 3850);
DISPLAY 0.872340 (-5950 3850);
PAINT GREEN (-5950 3850);
DISPLAY INVISIBLE (-5950 3850);
FORCEPROP 1 LAST HDL_TAP TRUE
J 2
(-6275 3675);
DISPLAY 0.872340 (-6275 3675);
DISPLAY INVISIBLE (-6275 3675);
FORCEPROP 1 LAST PATH I292
J 2
(-5948 3800);
DISPLAY 0.872340 (-5948 3800);
PAINT GREEN (-5948 3800);
DISPLAY INVISIBLE (-5948 3800);
FORCEADD TAP..1
R 2
(-5950 3750);
FORCEPROP 3 LASTPIN (-5900 3750) SIG_NAME M_F_CPU1_SA_CA<5>
J 0
(-5890 3760);
DISPLAY 0.659574 (-5890 3760);
PAINT MONO (-5890 3760);
DISPLAY INVISIBLE (-5890 3760);
FORCEPROP 1 LASTPIN (-5900 3750) BN 5
J 2
(-5888 3758);
DISPLAY 0.489362 (-5888 3758);
PAINT GREEN (-5888 3758);
FORCEPROP 2 LAST CDS_LIB mstr_standard
J 0
(-5950 3750);
DISPLAY 0.723404 (-5950 3750);
PAINT MONO (-5950 3750);
DISPLAY INVISIBLE (-5950 3750);
FORCEPROP 1 LAST BODY_TYPE PLUMBING
J 2
(-5950 3800);
DISPLAY 0.872340 (-5950 3800);
PAINT GREEN (-5950 3800);
DISPLAY INVISIBLE (-5950 3800);
FORCEPROP 1 LAST HDL_TAP TRUE
J 2
(-6275 3625);
DISPLAY 0.872340 (-6275 3625);
DISPLAY INVISIBLE (-6275 3625);
FORCEPROP 1 LAST PATH I293
J 2
(-5948 3750);
DISPLAY 0.872340 (-5948 3750);
PAINT GREEN (-5948 3750);
DISPLAY INVISIBLE (-5948 3750);
FORCEADD TAP..1
R 2
(-5950 3700);
FORCEPROP 3 LASTPIN (-5900 3700) SIG_NAME M_F_CPU1_SA_CA<6>
J 0
(-5890 3710);
DISPLAY 0.659574 (-5890 3710);
PAINT MONO (-5890 3710);
DISPLAY INVISIBLE (-5890 3710);
FORCEPROP 1 LASTPIN (-5900 3700) BN 6
J 2
(-5888 3708);
DISPLAY 0.489362 (-5888 3708);
PAINT GREEN (-5888 3708);
FORCEPROP 2 LAST CDS_LIB mstr_standard
J 0
(-5950 3700);
DISPLAY 0.723404 (-5950 3700);
PAINT MONO (-5950 3700);
DISPLAY INVISIBLE (-5950 3700);
FORCEPROP 1 LAST BODY_TYPE PLUMBING
J 2
(-5950 3750);
DISPLAY 0.872340 (-5950 3750);
PAINT GREEN (-5950 3750);
DISPLAY INVISIBLE (-5950 3750);
FORCEPROP 1 LAST HDL_TAP TRUE
J 2
(-6275 3575);
DISPLAY 0.872340 (-6275 3575);
DISPLAY INVISIBLE (-6275 3575);
FORCEPROP 1 LAST PATH I294
J 2
(-5948 3700);
DISPLAY 0.872340 (-5948 3700);
PAINT GREEN (-5948 3700);
DISPLAY INVISIBLE (-5948 3700);
FORCEADD TAP..1
R 2
(-5950 3600);
FORCEPROP 3 LASTPIN (-5900 3600) SIG_NAME M_F_CPU1_SB_CA<0>
J 0
(-5890 3610);
DISPLAY 0.659574 (-5890 3610);
PAINT MONO (-5890 3610);
DISPLAY INVISIBLE (-5890 3610);
FORCEPROP 1 LASTPIN (-5900 3600) BN 0
J 2
(-5888 3608);
DISPLAY 0.489362 (-5888 3608);
PAINT GREEN (-5888 3608);
FORCEPROP 2 LAST CDS_LIB mstr_standard
J 0
(-5950 3600);
DISPLAY 0.723404 (-5950 3600);
PAINT MONO (-5950 3600);
DISPLAY INVISIBLE (-5950 3600);
FORCEPROP 1 LAST BODY_TYPE PLUMBING
J 2
(-5950 3650);
DISPLAY 0.872340 (-5950 3650);
PAINT GREEN (-5950 3650);
DISPLAY INVISIBLE (-5950 3650);
FORCEPROP 1 LAST HDL_TAP TRUE
J 2
(-6275 3475);
DISPLAY 0.872340 (-6275 3475);
DISPLAY INVISIBLE (-6275 3475);
FORCEPROP 1 LAST PATH I295
J 2
(-5948 3600);
DISPLAY 0.872340 (-5948 3600);
PAINT GREEN (-5948 3600);
DISPLAY INVISIBLE (-5948 3600);
FORCEADD TAP..1
R 2
(-5950 3500);
FORCEPROP 3 LASTPIN (-5900 3500) SIG_NAME M_F_CPU1_SB_CA<2>
J 0
(-5890 3510);
DISPLAY 0.659574 (-5890 3510);
PAINT MONO (-5890 3510);
DISPLAY INVISIBLE (-5890 3510);
FORCEPROP 1 LASTPIN (-5900 3500) BN 2
J 2
(-5888 3508);
DISPLAY 0.489362 (-5888 3508);
PAINT GREEN (-5888 3508);
FORCEPROP 2 LAST CDS_LIB mstr_standard
J 0
(-5950 3500);
DISPLAY 0.723404 (-5950 3500);
PAINT MONO (-5950 3500);
DISPLAY INVISIBLE (-5950 3500);
FORCEPROP 1 LAST BODY_TYPE PLUMBING
J 2
(-5950 3550);
DISPLAY 0.872340 (-5950 3550);
PAINT GREEN (-5950 3550);
DISPLAY INVISIBLE (-5950 3550);
FORCEPROP 1 LAST HDL_TAP TRUE
J 2
(-6275 3375);
DISPLAY 0.872340 (-6275 3375);
DISPLAY INVISIBLE (-6275 3375);
FORCEPROP 1 LAST PATH I296
J 2
(-5948 3500);
DISPLAY 0.872340 (-5948 3500);
PAINT GREEN (-5948 3500);
DISPLAY INVISIBLE (-5948 3500);
FORCEADD TAP..1
R 2
(-5950 3550);
FORCEPROP 3 LASTPIN (-5900 3550) SIG_NAME M_F_CPU1_SB_CA<1>
J 0
(-5890 3560);
DISPLAY 0.659574 (-5890 3560);
PAINT MONO (-5890 3560);
DISPLAY INVISIBLE (-5890 3560);
FORCEPROP 1 LASTPIN (-5900 3550) BN 1
J 2
(-5888 3558);
DISPLAY 0.489362 (-5888 3558);
PAINT GREEN (-5888 3558);
FORCEPROP 2 LAST CDS_LIB mstr_standard
J 0
(-5950 3550);
DISPLAY 0.723404 (-5950 3550);
PAINT MONO (-5950 3550);
DISPLAY INVISIBLE (-5950 3550);
FORCEPROP 1 LAST BODY_TYPE PLUMBING
J 2
(-5950 3600);
DISPLAY 0.872340 (-5950 3600);
PAINT GREEN (-5950 3600);
DISPLAY INVISIBLE (-5950 3600);
FORCEPROP 1 LAST HDL_TAP TRUE
J 2
(-6275 3425);
DISPLAY 0.872340 (-6275 3425);
DISPLAY INVISIBLE (-6275 3425);
FORCEPROP 1 LAST PATH I297
J 2
(-5948 3550);
DISPLAY 0.872340 (-5948 3550);
PAINT GREEN (-5948 3550);
DISPLAY INVISIBLE (-5948 3550);
FORCEADD TAP..1
R 2
(-5950 3450);
FORCEPROP 3 LASTPIN (-5900 3450) SIG_NAME M_F_CPU1_SB_CA<3>
J 0
(-5890 3460);
DISPLAY 0.659574 (-5890 3460);
PAINT MONO (-5890 3460);
DISPLAY INVISIBLE (-5890 3460);
FORCEPROP 1 LASTPIN (-5900 3450) BN 3
J 2
(-5888 3458);
DISPLAY 0.489362 (-5888 3458);
PAINT GREEN (-5888 3458);
FORCEPROP 2 LAST CDS_LIB mstr_standard
J 0
(-5950 3450);
DISPLAY 0.723404 (-5950 3450);
PAINT MONO (-5950 3450);
DISPLAY INVISIBLE (-5950 3450);
FORCEPROP 1 LAST BODY_TYPE PLUMBING
J 2
(-5950 3500);
DISPLAY 0.872340 (-5950 3500);
PAINT GREEN (-5950 3500);
DISPLAY INVISIBLE (-5950 3500);
FORCEPROP 1 LAST HDL_TAP TRUE
J 2
(-6275 3325);
DISPLAY 0.872340 (-6275 3325);
DISPLAY INVISIBLE (-6275 3325);
FORCEPROP 1 LAST PATH I298
J 2
(-5948 3450);
DISPLAY 0.872340 (-5948 3450);
PAINT GREEN (-5948 3450);
DISPLAY INVISIBLE (-5948 3450);
FORCEADD TAP..1
R 2
(-5950 3400);
FORCEPROP 3 LASTPIN (-5900 3400) SIG_NAME M_F_CPU1_SB_CA<4>
J 0
(-5890 3410);
DISPLAY 0.659574 (-5890 3410);
PAINT MONO (-5890 3410);
DISPLAY INVISIBLE (-5890 3410);
FORCEPROP 1 LASTPIN (-5900 3400) BN 4
J 2
(-5888 3408);
DISPLAY 0.489362 (-5888 3408);
PAINT GREEN (-5888 3408);
FORCEPROP 2 LAST CDS_LIB mstr_standard
J 0
(-5950 3400);
DISPLAY 0.723404 (-5950 3400);
PAINT MONO (-5950 3400);
DISPLAY INVISIBLE (-5950 3400);
FORCEPROP 1 LAST BODY_TYPE PLUMBING
J 2
(-5950 3450);
DISPLAY 0.872340 (-5950 3450);
PAINT GREEN (-5950 3450);
DISPLAY INVISIBLE (-5950 3450);
FORCEPROP 1 LAST HDL_TAP TRUE
J 2
(-6275 3275);
DISPLAY 0.872340 (-6275 3275);
DISPLAY INVISIBLE (-6275 3275);
FORCEPROP 1 LAST PATH I299
J 2
(-5948 3400);
DISPLAY 0.872340 (-5948 3400);
PAINT GREEN (-5948 3400);
DISPLAY INVISIBLE (-5948 3400);
FORCEADD TAP..1
R 2
(-5950 3350);
FORCEPROP 3 LASTPIN (-5900 3350) SIG_NAME M_F_CPU1_SB_CA<5>
J 0
(-5890 3360);
DISPLAY 0.659574 (-5890 3360);
PAINT MONO (-5890 3360);
DISPLAY INVISIBLE (-5890 3360);
FORCEPROP 1 LASTPIN (-5900 3350) BN 5
J 2
(-5888 3358);
DISPLAY 0.489362 (-5888 3358);
PAINT GREEN (-5888 3358);
FORCEPROP 2 LAST CDS_LIB mstr_standard
J 0
(-5950 3350);
DISPLAY 0.723404 (-5950 3350);
PAINT MONO (-5950 3350);
DISPLAY INVISIBLE (-5950 3350);
FORCEPROP 1 LAST BODY_TYPE PLUMBING
J 2
(-5950 3400);
DISPLAY 0.872340 (-5950 3400);
PAINT GREEN (-5950 3400);
DISPLAY INVISIBLE (-5950 3400);
FORCEPROP 1 LAST HDL_TAP TRUE
J 2
(-6275 3225);
DISPLAY 0.872340 (-6275 3225);
DISPLAY INVISIBLE (-6275 3225);
FORCEPROP 1 LAST PATH I300
J 2
(-5948 3350);
DISPLAY 0.872340 (-5948 3350);
PAINT GREEN (-5948 3350);
DISPLAY INVISIBLE (-5948 3350);
FORCEADD TAP..1
R 2
(-5950 3300);
FORCEPROP 3 LASTPIN (-5900 3300) SIG_NAME M_F_CPU1_SB_CA<6>
J 0
(-5890 3310);
DISPLAY 0.659574 (-5890 3310);
PAINT MONO (-5890 3310);
DISPLAY INVISIBLE (-5890 3310);
FORCEPROP 1 LASTPIN (-5900 3300) BN 6
J 2
(-5888 3308);
DISPLAY 0.489362 (-5888 3308);
PAINT GREEN (-5888 3308);
FORCEPROP 2 LAST CDS_LIB mstr_standard
J 0
(-5950 3300);
DISPLAY 0.723404 (-5950 3300);
PAINT MONO (-5950 3300);
DISPLAY INVISIBLE (-5950 3300);
FORCEPROP 1 LAST BODY_TYPE PLUMBING
J 2
(-5950 3350);
DISPLAY 0.872340 (-5950 3350);
PAINT GREEN (-5950 3350);
DISPLAY INVISIBLE (-5950 3350);
FORCEPROP 1 LAST HDL_TAP TRUE
J 2
(-6275 3175);
DISPLAY 0.872340 (-6275 3175);
DISPLAY INVISIBLE (-6275 3175);
FORCEPROP 1 LAST PATH I301
J 2
(-5948 3300);
DISPLAY 0.872340 (-5948 3300);
PAINT GREEN (-5948 3300);
DISPLAY INVISIBLE (-5948 3300);
FORCEADD OFFPAGE..2
R 2
(-6550 4025);
FORCEPROP 2 LAST $XR0 103 
J 0
(-6805 4025);
DISPLAY 0.638298 (-6805 4025);
PAINT MONO (-6805 4025);
FORCEPROP 2 LAST CDS_LIB standard
J 0
(-6550 4025);
DISPLAY INVISIBLE (-6550 4025);
FORCEPROP 1 LAST OFFPAGE TRUE
J 2
(-6875 3900);
DISPLAY 0.872340 (-6875 3900);
PAINT GREEN (-6875 3900);
DISPLAY INVISIBLE (-6875 3900);
FORCEPROP 1 LAST COMMENT_BODY TRUE
J 2
(-6505 3930);
DISPLAY 0.872340 (-6505 3930);
PAINT GREEN (-6505 3930);
DISPLAY INVISIBLE (-6505 3930);
FORCEPROP 2 LAST PATH I302
J 0
(-6800 4075);
DISPLAY 1.021277 (-6800 4075);
DISPLAY INVISIBLE (-6800 4075);
FORCEADD OFFPAGE..2
R 2
(-6550 3625);
FORCEPROP 2 LAST $XR0 103 
J 0
(-6805 3625);
DISPLAY 0.638298 (-6805 3625);
PAINT MONO (-6805 3625);
FORCEPROP 2 LAST CDS_LIB standard
J 0
(-6550 3625);
DISPLAY INVISIBLE (-6550 3625);
FORCEPROP 1 LAST OFFPAGE TRUE
J 2
(-6875 3500);
DISPLAY 0.872340 (-6875 3500);
PAINT GREEN (-6875 3500);
DISPLAY INVISIBLE (-6875 3500);
FORCEPROP 1 LAST COMMENT_BODY TRUE
J 2
(-6505 3530);
DISPLAY 0.872340 (-6505 3530);
PAINT GREEN (-6505 3530);
DISPLAY INVISIBLE (-6505 3530);
FORCEPROP 2 LAST PATH I303
J 0
(-6800 3675);
DISPLAY 1.021277 (-6800 3675);
DISPLAY INVISIBLE (-6800 3675);
FORCEADD OFFPAGE..2
R 2
(-6550 3150);
FORCEPROP 2 LAST $XR0 103 
J 0
(-6805 3150);
DISPLAY 0.638298 (-6805 3150);
PAINT MONO (-6805 3150);
FORCEPROP 2 LAST CDS_LIB standard
J 0
(-6550 3150);
DISPLAY INVISIBLE (-6550 3150);
FORCEPROP 1 LAST OFFPAGE TRUE
J 2
(-6875 3025);
DISPLAY 0.872340 (-6875 3025);
PAINT GREEN (-6875 3025);
DISPLAY INVISIBLE (-6875 3025);
FORCEPROP 1 LAST COMMENT_BODY TRUE
J 2
(-6505 3055);
DISPLAY 0.872340 (-6505 3055);
PAINT GREEN (-6505 3055);
DISPLAY INVISIBLE (-6505 3055);
FORCEPROP 2 LAST PATH I304
J 0
(-6800 3200);
DISPLAY 1.021277 (-6800 3200);
DISPLAY INVISIBLE (-6800 3200);
FORCEADD OFFPAGE..2
R 2
(-6550 3100);
FORCEPROP 2 LAST $XR0 103 
J 0
(-6805 3100);
DISPLAY 0.638298 (-6805 3100);
PAINT MONO (-6805 3100);
FORCEPROP 2 LAST CDS_LIB standard
J 0
(-6550 3100);
DISPLAY INVISIBLE (-6550 3100);
FORCEPROP 1 LAST OFFPAGE TRUE
J 2
(-6875 2975);
DISPLAY 0.872340 (-6875 2975);
PAINT GREEN (-6875 2975);
DISPLAY INVISIBLE (-6875 2975);
FORCEPROP 1 LAST COMMENT_BODY TRUE
J 2
(-6505 3005);
DISPLAY 0.872340 (-6505 3005);
PAINT GREEN (-6505 3005);
DISPLAY INVISIBLE (-6505 3005);
FORCEPROP 2 LAST PATH I305
J 0
(-6800 3150);
DISPLAY 1.021277 (-6800 3150);
DISPLAY INVISIBLE (-6800 3150);
FORCEADD OFFPAGE..2
R 2
(-6550 3000);
FORCEPROP 2 LAST $XR0 103 
J 0
(-6805 3000);
DISPLAY 0.638298 (-6805 3000);
PAINT MONO (-6805 3000);
FORCEPROP 2 LAST CDS_LIB standard
J 0
(-6550 3000);
DISPLAY INVISIBLE (-6550 3000);
FORCEPROP 1 LAST OFFPAGE TRUE
J 2
(-6875 2875);
DISPLAY 0.872340 (-6875 2875);
PAINT GREEN (-6875 2875);
DISPLAY INVISIBLE (-6875 2875);
FORCEPROP 1 LAST COMMENT_BODY TRUE
J 2
(-6505 2905);
DISPLAY 0.872340 (-6505 2905);
PAINT GREEN (-6505 2905);
DISPLAY INVISIBLE (-6505 2905);
FORCEPROP 2 LAST PATH I306
J 0
(-6800 3050);
DISPLAY 1.021277 (-6800 3050);
DISPLAY INVISIBLE (-6800 3050);
FORCEADD OFFPAGE..2
R 2
(-6550 2950);
FORCEPROP 2 LAST $XR0 103 
J 0
(-6805 2950);
DISPLAY 0.638298 (-6805 2950);
PAINT MONO (-6805 2950);
FORCEPROP 2 LAST CDS_LIB standard
J 0
(-6550 2950);
DISPLAY INVISIBLE (-6550 2950);
FORCEPROP 1 LAST OFFPAGE TRUE
J 2
(-6875 2825);
DISPLAY 0.872340 (-6875 2825);
PAINT GREEN (-6875 2825);
DISPLAY INVISIBLE (-6875 2825);
FORCEPROP 1 LAST COMMENT_BODY TRUE
J 2
(-6505 2855);
DISPLAY 0.872340 (-6505 2855);
PAINT GREEN (-6505 2855);
DISPLAY INVISIBLE (-6505 2855);
FORCEPROP 2 LAST PATH I307
J 0
(-6800 3000);
DISPLAY 1.021277 (-6800 3000);
DISPLAY INVISIBLE (-6800 3000);
FORCEADD OFFPAGE..1
(-6550 2850);
FORCEPROP 2 LAST $XR0 103 
J 0
(-6832 2850);
DISPLAY 0.638298 (-6832 2850);
PAINT MONO (-6832 2850);
FORCEPROP 2 LAST CDS_LIB standard
J 0
(-6550 2850);
DISPLAY INVISIBLE (-6550 2850);
FORCEPROP 1 LAST OFFPAGE TRUE
J 0
(-6225 2725);
DISPLAY 0.872340 (-6225 2725);
PAINT GREEN (-6225 2725);
DISPLAY INVISIBLE (-6225 2725);
FORCEPROP 1 LAST COMMENT_BODY TRUE
J 0
(-6425 2750);
DISPLAY 0.872340 (-6425 2750);
PAINT GREEN (-6425 2750);
DISPLAY INVISIBLE (-6425 2750);
FORCEPROP 2 LAST PATH I308
J 0
(-6825 2900);
DISPLAY 1.021277 (-6825 2900);
DISPLAY INVISIBLE (-6825 2900);
FORCEADD OFFPAGE..5
(-6550 2750);
FORCEPROP 2 LAST $XR0 103 
J 0
(-6805 2750);
DISPLAY 0.638298 (-6805 2750);
PAINT MONO (-6805 2750);
FORCEPROP 2 LAST CDS_LIB mstr_standard
J 0
(-6550 2750);
DISPLAY INVISIBLE (-6550 2750);
FORCEPROP 1 LAST OFFPAGE TRUE
J 0
(-6225 2625);
DISPLAY 0.872340 (-6225 2625);
PAINT GREEN (-6225 2625);
DISPLAY INVISIBLE (-6225 2625);
FORCEPROP 1 LAST COMMENT_BODY TRUE
J 0
(-6450 2675);
DISPLAY 0.872340 (-6450 2675);
PAINT GREEN (-6450 2675);
DISPLAY INVISIBLE (-6450 2675);
FORCEPROP 2 LAST PATH I309
J 0
(-6800 2800);
DISPLAY 1.021277 (-6800 2800);
DISPLAY INVISIBLE (-6800 2800);
FORCEADD OFFPAGE..2
R 2
(-6550 2650);
FORCEPROP 2 LAST $XR0 103 
J 0
(-6805 2650);
DISPLAY 0.638298 (-6805 2650);
PAINT MONO (-6805 2650);
FORCEPROP 2 LAST CDS_LIB standard
J 0
(-6550 2650);
DISPLAY INVISIBLE (-6550 2650);
FORCEPROP 1 LAST OFFPAGE TRUE
J 2
(-6875 2525);
DISPLAY 0.872340 (-6875 2525);
PAINT GREEN (-6875 2525);
DISPLAY INVISIBLE (-6875 2525);
FORCEPROP 1 LAST COMMENT_BODY TRUE
J 2
(-6505 2555);
DISPLAY 0.872340 (-6505 2555);
PAINT GREEN (-6505 2555);
DISPLAY INVISIBLE (-6505 2555);
FORCEPROP 2 LAST PATH I310
J 0
(-6800 2700);
DISPLAY 1.021277 (-6800 2700);
DISPLAY INVISIBLE (-6800 2700);
FORCEADD OFFPAGE..2
R 2
(-6550 2600);
FORCEPROP 2 LAST $XR0 103 
J 0
(-6805 2600);
DISPLAY 0.638298 (-6805 2600);
PAINT MONO (-6805 2600);
FORCEPROP 2 LAST CDS_LIB standard
J 0
(-6550 2600);
DISPLAY INVISIBLE (-6550 2600);
FORCEPROP 1 LAST OFFPAGE TRUE
J 2
(-6875 2475);
DISPLAY 0.872340 (-6875 2475);
PAINT GREEN (-6875 2475);
DISPLAY INVISIBLE (-6875 2475);
FORCEPROP 1 LAST COMMENT_BODY TRUE
J 2
(-6505 2505);
DISPLAY 0.872340 (-6505 2505);
PAINT GREEN (-6505 2505);
DISPLAY INVISIBLE (-6505 2505);
FORCEPROP 2 LAST PATH I311
J 0
(-6800 2650);
DISPLAY 1.021277 (-6800 2650);
DISPLAY INVISIBLE (-6800 2650);
FORCEADD OFFPAGE..1
(-6550 2500);
FORCEPROP 2 LAST $XR0 103 
J 0
(-6832 2500);
DISPLAY 0.638298 (-6832 2500);
PAINT MONO (-6832 2500);
FORCEPROP 2 LAST CDS_LIB standard
J 0
(-6550 2500);
DISPLAY INVISIBLE (-6550 2500);
FORCEPROP 1 LAST OFFPAGE TRUE
J 0
(-6225 2375);
DISPLAY 0.872340 (-6225 2375);
PAINT GREEN (-6225 2375);
DISPLAY INVISIBLE (-6225 2375);
FORCEPROP 1 LAST COMMENT_BODY TRUE
J 0
(-6425 2400);
DISPLAY 0.872340 (-6425 2400);
PAINT GREEN (-6425 2400);
DISPLAY INVISIBLE (-6425 2400);
FORCEPROP 2 LAST PATH I312
J 0
(-6825 2550);
DISPLAY 1.021277 (-6825 2550);
DISPLAY INVISIBLE (-6825 2550);
FORCEADD OFFPAGE..5
(-6550 2400);
FORCEPROP 2 LAST $XR0 103 
J 0
(-6805 2400);
DISPLAY 0.638298 (-6805 2400);
PAINT MONO (-6805 2400);
FORCEPROP 2 LAST CDS_LIB standard
J 0
(-6550 2400);
DISPLAY INVISIBLE (-6550 2400);
FORCEPROP 1 LAST OFFPAGE TRUE
J 0
(-6225 2275);
DISPLAY 0.872340 (-6225 2275);
PAINT GREEN (-6225 2275);
DISPLAY INVISIBLE (-6225 2275);
FORCEPROP 1 LAST COMMENT_BODY TRUE
J 0
(-6450 2325);
DISPLAY 0.872340 (-6450 2325);
PAINT GREEN (-6450 2325);
DISPLAY INVISIBLE (-6450 2325);
FORCEPROP 2 LAST PATH I313
J 0
(-6800 2450);
DISPLAY 1.021277 (-6800 2450);
DISPLAY INVISIBLE (-6800 2450);
FORCEADD Q_RES..1
(-6625 2300);
FORCEPROP 1 LAST LOCATION R505
J 0
(-6950 2300);
DISPLAY 0.489362 (-6950 2300);
PAINT SKYBLUE (-6950 2300);
FORCEPROP 0 LAST $SEC 1
J 0
(-6800 2350);
DISPLAY 0.680851 (-6800 2350);
PAINT MONO (-6800 2350);
DISPLAY INVISIBLE (-6800 2350);
FORCEPROP 0 LAST CDS_SEC 1
J 0
(-6800 2350);
DISPLAY 1.021277 (-6800 2350);
DISPLAY INVISIBLE (-6800 2350);
FORCEPROP 1 LASTPIN (-6725 2300) $PN 1
J 0
(-6713 2312);
DISPLAY 0.489362 (-6713 2312);
PAINT MONO (-6713 2312);
FORCEPROP 1 LASTPIN (-6525 2300) $PN 2
J 0
(-6563 2312);
DISPLAY 0.489362 (-6563 2312);
PAINT MONO (-6563 2312);
FORCEPROP 1 LAST PACK_TYPE 0402LF
J 0
(-6950 2275);
DISPLAY 0.489362 (-6950 2275);
PAINT SKYBLUE (-6950 2275);
FORCEPROP 1 LAST TOLERANCE 1%
J 0
(-6350 2300);
DISPLAY 0.489362 (-6350 2300);
PAINT SKYBLUE (-6350 2300);
FORCEPROP 1 LAST VALUE 15
J 2
(-6300 2300);
DISPLAY 0.489362 (-6300 2300);
PAINT SKYBLUE (-6300 2300);
FORCEPROP 1 LAST MATERIAL CHIP
J 0
(-6750 2425);
DISPLAY 0.638298 (-6750 2425);
PAINT SKYBLUE (-6750 2425);
DISPLAY INVISIBLE (-6750 2425);
FORCEPROP 1 LAST WATTAGE 1/16W
J 2
(-6400 2425);
DISPLAY 0.638298 (-6400 2425);
PAINT SKYBLUE (-6400 2425);
DISPLAY INVISIBLE (-6400 2425);
FORCEPROP 2 LAST CDS_LIB pure_quanta
J 0
(-6625 2300);
DISPLAY INVISIBLE (-6625 2300);
FORCEPROP 1 LAST PATH I314
J 0
(-6675 2450);
DISPLAY 0.978723 (-6675 2450);
PAINT WHITE (-6675 2450);
DISPLAY INVISIBLE (-6675 2450);
FORCEPROP 1 LAST PART_NUMBER CS01502FB03
J 0
(-6500 2275);
DISPLAY 0.489362 (-6500 2275);
PAINT SKYBLUE (-6500 2275);
DISPLAY INVISIBLE (-6500 2275);
FORCEADD OFFPAGE..5
(-6550 2200);
FORCEPROP 2 LAST $XR0 103 
J 0
(-6805 2200);
DISPLAY 0.638298 (-6805 2200);
PAINT MONO (-6805 2200);
FORCEPROP 2 LAST CDS_LIB standard
J 0
(-6550 2200);
DISPLAY INVISIBLE (-6550 2200);
FORCEPROP 1 LAST OFFPAGE TRUE
J 0
(-6225 2075);
DISPLAY 0.872340 (-6225 2075);
PAINT GREEN (-6225 2075);
DISPLAY INVISIBLE (-6225 2075);
FORCEPROP 1 LAST COMMENT_BODY TRUE
J 0
(-6450 2125);
DISPLAY 0.872340 (-6450 2125);
PAINT GREEN (-6450 2125);
DISPLAY INVISIBLE (-6450 2125);
FORCEPROP 2 LAST PATH I315
J 0
(-6800 2250);
DISPLAY 1.021277 (-6800 2250);
DISPLAY INVISIBLE (-6800 2250);
FORCEADD OFFPAGE..1
(-7500 2300);
FORCEPROP 2 LAST $XR0 103 
J 0
(-7752 2300);
DISPLAY 0.638298 (-7752 2300);
PAINT MONO (-7752 2300);
FORCEPROP 2 LAST CDS_LIB mstr_standard
J 0
(-7500 2300);
DISPLAY INVISIBLE (-7500 2300);
FORCEPROP 1 LAST OFFPAGE TRUE
J 0
(-7175 2175);
DISPLAY 0.872340 (-7175 2175);
PAINT GREEN (-7175 2175);
DISPLAY INVISIBLE (-7175 2175);
FORCEPROP 1 LAST COMMENT_BODY TRUE
J 0
(-7375 2200);
DISPLAY 0.872340 (-7375 2200);
PAINT GREEN (-7375 2200);
DISPLAY INVISIBLE (-7375 2200);
FORCEPROP 2 LAST PATH I316
J 0
(-7750 2350);
DISPLAY 1.021277 (-7750 2350);
DISPLAY INVISIBLE (-7750 2350);
FORCEADD CAD_NOTE..1
(-7700 2575);
FORCEPROP 0 LAST L1 R1963 PLACE CLOSE TO CPU < 25MM
J 0
(-7850 2450);
DISPLAY 0.617021 (-7850 2450);
PAINT WHITE (-7850 2450);
FORCEPROP 2 LAST CDS_LIB pure_quanta_power
J 0
(-7700 2575);
DISPLAY INVISIBLE (-7700 2575);
FORCEPROP 1 LAST COMMENT_BODY TRUE
J 0
(-7675 2675);
DISPLAY 0.574468 (-7675 2675);
PAINT WHITE (-7675 2675);
DISPLAY INVISIBLE (-7675 2675);
FORCEADD QUANTA_TITLE_BLOCK_C..1
(-100 100);
FORCEPROP 0 LAST CDS_CON_LAST_MODIFIED Thu Sep 14 16:11:56 2023
J 0
(-1985 115);
DISPLAY INVISIBLE (-1985 115);
FORCEPROP 1 LAST CUSTOM_TXT_CDS <CON_LAST_MODIFIED>
J 0
(-1985 115);
DISPLAY 0.978723 (-1985 115);
FORCEPROP 2 LAST CUSTOM_TXT_CDS <XR_PAGE_TITLE>
J 0
(-7990 5350);
DISPLAY 0.638298 (-7990 5350);
PAINT PINK (-7990 5350);
DISPLAY INVISIBLE (-7990 5350);
FORCEPROP 1 LAST CUSTOM_TXT_CDS <NAME_2>
J 0
(-3275 150);
FORCEPROP 1 LAST CUSTOM_TXT_CDS <NAME_1>
J 0
(-3275 275);
FORCEPROP 1 LAST CUSTOM_TXT_CDS <Q_NUMBER>
J 0
(-1503 203);
DISPLAY 1.212766 (-1503 203);
FORCEPROP 1 LAST CUSTOM_TXT_CDS <Q_PROJ>
J 0
(-2482 202);
DISPLAY 1.212766 (-2482 202);
FORCEPROP 1 LAST CUSTOM_TXT_CDS <Q_REV>
J 0
(-284 203);
DISPLAY 1.212766 (-284 203);
FORCEPROP 1 LAST CUSTOM_TXT_CDS <CON_PAGE_NUM> OF <CON_TOTAL_PAGES>
J 0
(-546 118);
DISPLAY 0.978723 (-546 118);
FORCEPROP 1 LAST Q_TITLE CPU1 DDR CHF
J 0
(-9400 175);
DISPLAY 2.446809 (-9400 175);
PAINT GREEN (-9400 175);
FORCEPROP 2 LAST PAGE_BORDER TRUE
J 0
(-7990 5350);
DISPLAY 0.638298 (-7990 5350);
PAINT PINK (-7990 5350);
DISPLAY INVISIBLE (-7990 5350);
FORCEPROP 2 LAST CDS_LIB pure_quanta
J 0
(-100 100);
DISPLAY INVISIBLE (-100 100);
FORCEPROP 1 LAST CDS_LMAN_SYM_OUTLINE -9475,6775,100,-125
J 0
(-100 100);
DISPLAY 0.468085 (-100 100);
PAINT GREEN (-100 100);
DISPLAY INVISIBLE (-100 100);
FORCEPROP 2 LAST CDS_XR_PAGE_TITLE CR-42 : @T6G_MB_LIB.T6G(SCH_1):PAGE42
J 0
(-7990 5350);
DISPLAY 0.638298 (-7990 5350);
PAINT PINK (-7990 5350);
DISPLAY INVISIBLE (-7990 5350);
FORCEPROP 1 LAST Q_DEPT BU9
J 1
(-3863 149);
DISPLAY 1.957447 (-3863 149);
PAINT GREEN (-3863 149);
DISPLAY INVISIBLE (-3863 149);
FORCEPROP 1 LAST COMMENT_BODY TRUE
J 0
(-88 87);
DISPLAY 0.978723 (-88 87);
PAINT GREEN (-88 87);
DISPLAY INVISIBLE (-88 87);
WIRE 17 -1 (-3275 6175)(-2650 6175);
FORCEPROP 2 LAST SIG_NAME M_F_CPU1_SA_DQ<31:0>
J 2
(-2710 6185);
DISPLAY 0.489362 (-2710 6185);
WIRE 17 -1 (-3275 5825)(-3275 5725);
WIRE 17 -1 (-3275 5875)(-3275 5825);
WIRE 17 -1 (-3275 5725)(-3275 5675);
WIRE 17 -1 (-3275 5675)(-3275 5625);
WIRE 17 -1 (-3275 5925)(-3275 5875);
WIRE 17 -1 (-3275 5975)(-3275 5925);
WIRE 17 -1 (-3275 5625)(-3275 5575);
WIRE 17 -1 (-3275 5575)(-3275 5525);
WIRE 17 -1 (-3275 6025)(-3275 5975);
WIRE 17 -1 (-3275 6075)(-3275 6025);
WIRE 17 -1 (-3275 5525)(-3275 5475);
WIRE 17 -1 (-3275 5475)(-3275 5425);
WIRE 17 -1 (-3275 6125)(-3275 6075);
WIRE 17 -1 (-3275 6175)(-3275 6125);
WIRE 17 -1 (-3275 5425)(-3275 5375);
WIRE 17 -1 (-3275 5275)(-3275 5375);
WIRE 17 -1 (-3275 5225)(-3275 5275);
WIRE 17 -1 (-3275 5175)(-3275 5225);
WIRE 17 -1 (-3275 5125)(-3275 5175);
WIRE 17 -1 (-3275 5125)(-3275 5075);
WIRE 17 -1 (-3275 5075)(-3275 5025);
WIRE 17 -1 (-3275 5025)(-3275 4975);
WIRE 17 -1 (-3275 4975)(-3275 4925);
WIRE 17 -1 (-3275 4925)(-3275 4825);
WIRE 17 -1 (-3275 4825)(-3275 4775);
WIRE 17 -1 (-3275 4775)(-3275 4725);
WIRE 17 -1 (-3275 4725)(-3275 4675);
WIRE 17 -1 (-3275 4625)(-3275 4675);
WIRE 17 -1 (-3275 4575)(-3275 4625);
WIRE 17 -1 (-3275 4525)(-3275 4575);
WIRE 17 -1 (-3275 4475)(-3275 4525);
WIRE 17 -1 (-3275 4375)(-2650 4375);
FORCEPROP 2 LAST SIG_NAME M_F_CPU1_SB_DQ<31:0>
J 2
(-2710 4385);
DISPLAY 0.489362 (-2710 4385);
WIRE 17 -1 (-3275 4375)(-3275 4325);
WIRE 17 -1 (-3275 4325)(-3275 4275);
WIRE 17 -1 (-3275 4275)(-3275 4225);
WIRE 17 -1 (-3275 4225)(-3275 4175);
WIRE 17 -1 (-3275 4175)(-3275 4125);
WIRE 17 -1 (-3275 4125)(-3275 4075);
WIRE 17 -1 (-3275 4075)(-3275 4025);
WIRE 17 -1 (-3275 4025)(-3275 3925);
WIRE 17 -1 (-3275 3925)(-3275 3875);
WIRE 17 -1 (-3275 3325)(-3275 3375);
WIRE 17 -1 (-3275 3325)(-3275 3275);
WIRE 17 -1 (-3275 3375)(-3275 3425);
WIRE 17 -1 (-3275 3425)(-3275 3475);
WIRE 17 -1 (-3275 3275)(-3275 3225);
WIRE 17 -1 (-3275 3225)(-3275 3175);
WIRE 17 -1 (-3275 3475)(-3275 3575);
WIRE 17 -1 (-3275 3625)(-3275 3575);
WIRE 17 -1 (-3275 3175)(-3275 3125);
WIRE 17 -1 (-3275 3125)(-3275 3025);
WIRE 17 -1 (-3275 3675)(-3275 3625);
WIRE 17 -1 (-3275 3725)(-3275 3675);
WIRE 17 -1 (-3275 3025)(-3275 2975);
WIRE 17 -1 (-3275 2975)(-3275 2925);
WIRE 17 -1 (-3275 3775)(-3275 3725);
WIRE 17 -1 (-3275 3825)(-3275 3775);
WIRE 17 -1 (-3275 2925)(-3275 2875);
WIRE 17 -1 (-3275 2825)(-3275 2875);
WIRE 17 -1 (-3275 3875)(-3275 3825);
WIRE 17 -1 (-3275 2775)(-3275 2825);
WIRE 17 -1 (-3275 2725)(-3275 2775);
WIRE 17 -1 (-3275 2675)(-3275 2725);
WIRE 17 -1 (-3275 2575)(-3275 2600);
WIRE 17 -1 (-3275 2575)(-3275 2525);
WIRE 17 -1 (-3275 2600)(-2775 2600);
FORCEPROP 2 LAST SIG_NAME M_F_CPU1_SA_CB<7:0>
J 2
(-2775 2610);
DISPLAY 0.489362 (-2775 2610);
WIRE 17 -1 (-3275 2475)(-3275 2525);
WIRE 17 -1 (-3275 2475)(-3275 2425);
WIRE 17 -1 (-3275 2375)(-3275 2425);
WIRE 17 -1 (-3275 2325)(-3275 2375);
WIRE 17 -1 (-3275 2275)(-3275 2325);
WIRE 17 -1 (-3275 2225)(-3275 2275);
WIRE 17 -1 (-3275 2125)(-3275 2150);
WIRE 17 -1 (-3275 2125)(-3275 2075);
WIRE 17 -1 (-3275 2150)(-2775 2150);
FORCEPROP 2 LAST SIG_NAME M_F_CPU1_SB_CB<7:0>
J 2
(-2775 2160);
DISPLAY 0.489362 (-2775 2160);
WIRE 17 -1 (-3275 2025)(-3275 2075);
WIRE 17 -1 (-3275 2025)(-3275 1975);
WIRE 17 -1 (-3275 1925)(-3275 1975);
WIRE 17 -1 (-3275 1875)(-3275 1925);
WIRE 17 -1 (-3275 1825)(-3275 1875);
WIRE 17 -1 (-3275 1775)(-3275 1825);
WIRE 17 -1 (-5800 6175)(-5800 6075);
WIRE 17 -1 (-5800 6175)(-6600 6175);
FORCEPROP 2 LAST SIG_NAME M_F_CPU1_SA_DQS_DP<9:0>
J 2
(-6035 6185);
DISPLAY 0.489362 (-6035 6185);
WIRE 17 -1 (-5800 5475)(-5800 5375);
WIRE 17 -1 (-5800 5475)(-5800 5575);
WIRE 17 -1 (-5800 5375)(-5800 5275);
WIRE 17 -1 (-5800 5575)(-5800 5675);
WIRE 17 -1 (-5800 5675)(-5800 5775);
WIRE 17 -1 (-5800 5875)(-5800 5775);
WIRE 17 -1 (-5800 5975)(-5800 5875);
WIRE 17 -1 (-5800 6075)(-5800 5975);
WIRE 17 -1 (-6000 6125)(-6000 6025);
FORCEPROP 2 LAST SIG_NAME M_F_CPU1_SA_DQS_DN<9:0>
J 2
(-6035 6135);
DISPLAY 0.489362 (-6035 6135);
WIRE 17 -1 (-6000 6025)(-6000 5925);
WIRE 17 -1 (-6000 5925)(-6000 5825);
WIRE 17 -1 (-6000 5825)(-6000 5725);
WIRE 17 -1 (-6000 5625)(-6000 5725);
WIRE 17 -1 (-6000 5525)(-6000 5625);
WIRE 17 -1 (-6000 5425)(-6000 5525);
WIRE 17 -1 (-6000 5425)(-6000 5325);
WIRE 17 -1 (-6000 5325)(-6000 5225);
WIRE 17 -1 (-6000 4475)(-6000 4575);
WIRE 17 -1 (-6000 4375)(-6000 4475);
WIRE 17 -1 (-6000 4575)(-6000 4675);
WIRE 17 -1 (-6000 4775)(-6000 4675);
WIRE 17 -1 (-6000 4375)(-6000 4275);
WIRE 17 -1 (-6000 4275)(-6000 4175);
WIRE 17 -1 (-6000 4875)(-6000 4775);
WIRE 17 -1 (-6000 4975)(-6000 4875);
WIRE 17 -1 (-6000 5075)(-6000 4975);
FORCEPROP 2 LAST SIG_NAME M_F_CPU1_SB_DQS_DN<9:0>
J 2
(-6035 5085);
DISPLAY 0.489362 (-6035 5085);
WIRE 17 -1 (-5800 5025)(-5800 4925);
WIRE 17 -1 (-5800 5125)(-5800 5025);
WIRE 17 -1 (-5800 4925)(-5800 4825);
WIRE 17 -1 (-5800 4825)(-5800 4725);
WIRE 17 -1 (-5800 5125)(-6600 5125);
FORCEPROP 2 LAST SIG_NAME M_F_CPU1_SB_DQS_DP<9:0>
J 2
(-6035 5135);
DISPLAY 0.489362 (-6035 5135);
WIRE 17 -1 (-5800 4625)(-5800 4725);
WIRE 17 -1 (-5800 4525)(-5800 4625);
WIRE 17 -1 (-5800 4425)(-5800 4525);
WIRE 17 -1 (-5800 4425)(-5800 4325);
WIRE 17 -1 (-5800 4325)(-5800 4225);
WIRE 17 -1 (-6000 3975)(-6000 4025);
WIRE 17 -1 (-6000 3925)(-6000 3975);
WIRE 17 -1 (-6000 4025)(-6500 4025);
FORCEPROP 2 LAST SIG_NAME M_F_CPU1_SA_CA<6:0>
J 0
(-6500 4035);
DISPLAY 0.489362 (-6500 4035);
WIRE 17 -1 (-6000 3575)(-6000 3625);
WIRE 17 -1 (-6000 3525)(-6000 3575);
WIRE 17 -1 (-6000 3625)(-6500 3625);
FORCEPROP 2 LAST SIG_NAME M_F_CPU1_SB_CA<6:0>
J 0
(-6500 3635);
DISPLAY 0.489362 (-6500 3635);
WIRE 17 -1 (-6000 3875)(-6000 3925);
WIRE 17 -1 (-6000 3475)(-6000 3525);
WIRE 17 -1 (-6000 3825)(-6000 3875);
WIRE 17 -1 (-6000 3775)(-6000 3825);
WIRE 17 -1 (-6000 3725)(-6000 3775);
WIRE 17 -1 (-6000 3425)(-6000 3475);
WIRE 17 -1 (-6000 3375)(-6000 3425);
WIRE 17 -1 (-6000 3325)(-6000 3375);
WIRE 17 -1 (-6000 6125)(-6600 6125);
WIRE 17 -1 (-6000 5075)(-6600 5075);
WIRE 16 -1 (-7450 2300)(-6725 2300);
FORCEPROP 2 LAST SIG_NAME M_F_CPU1_ALERT_N
J 0
(-7410 2310);
DISPLAY 0.489362 (-7410 2310);
WIRE 16 -1 (-6525 2300)(-5400 2300);
FORCEPROP 2 LAST SIG_NAME M_F_CPU1_ALERT_R_N
J 0
(-6235 2310);
DISPLAY 0.489362 (-6235 2310);
FORCEPROP 2 LASTPROP $XRERR UNIQUE?
J 0
(-6475 2310);
DISPLAY 0.638298 (-6475 2310);
PAINT MONO (-6475 2310);
DISPLAY INVISIBLE (-6475 2310);
WIRE 16 -1 (-6500 1350)(-5400 1350);
FORCEPROP 2 LAST SIG_NAME TP_M_F_CPU1_SA_TEST39F
J 0
(-6485 1360);
DISPLAY 0.489362 (-6485 1360);
FORCEPROP 2 LASTPROP $XRERR UNIQUE?
J 0
(-6740 1350);
DISPLAY 0.638298 (-6740 1350);
PAINT MONO (-6740 1350);
DISPLAY INVISIBLE (-6740 1350);
WIRE 16 -1 (-6500 3150)(-5400 3150);
FORCEPROP 2 LAST SIG_NAME M_F_CPU1_CLK_DP<0>
J 0
(-6500 3160);
DISPLAY 0.489362 (-6500 3160);
WIRE 16 -1 (-6500 3100)(-5400 3100);
FORCEPROP 2 LAST SIG_NAME M_F_CPU1_CLK_DN<0>
J 0
(-6500 3110);
DISPLAY 0.489362 (-6500 3110);
WIRE 16 -1 (-6500 3000)(-5400 3000);
FORCEPROP 2 LAST SIG_NAME M_F_CPU1_SA_CS_N<0>
J 0
(-6500 3010);
DISPLAY 0.489362 (-6500 3010);
WIRE 16 -1 (-6500 2950)(-5400 2950);
FORCEPROP 2 LAST SIG_NAME M_F_CPU1_SA_CS_N<1>
J 0
(-6500 2960);
DISPLAY 0.489362 (-6500 2960);
WIRE 16 -1 (-6500 2850)(-5400 2850);
FORCEPROP 2 LAST SIG_NAME M_F_CPU1_SA_RSP<0>
J 0
(-6500 2860);
DISPLAY 0.489362 (-6500 2860);
WIRE 16 -1 (-6500 2750)(-5400 2750);
FORCEPROP 2 LAST SIG_NAME M_F_CPU1_SA_PAR
J 0
(-6500 2760);
DISPLAY 0.489362 (-6500 2760);
WIRE 16 -1 (-6500 2650)(-5400 2650);
FORCEPROP 2 LAST SIG_NAME M_F_CPU1_SB_CS_N<0>
J 0
(-6500 2660);
DISPLAY 0.489362 (-6500 2660);
WIRE 16 -1 (-6500 2600)(-5400 2600);
FORCEPROP 2 LAST SIG_NAME M_F_CPU1_SB_CS_N<1>
J 0
(-6500 2610);
DISPLAY 0.489362 (-6500 2610);
WIRE 16 -1 (-6500 2500)(-5400 2500);
FORCEPROP 2 LAST SIG_NAME M_F_CPU1_SB_RSP<0>
J 0
(-6500 2510);
DISPLAY 0.489362 (-6500 2510);
WIRE 16 -1 (-6500 2400)(-5400 2400);
FORCEPROP 2 LAST SIG_NAME M_F_CPU1_SB_PAR
J 0
(-6500 2410);
DISPLAY 0.489362 (-6500 2410);
WIRE 16 -1 (-6500 2200)(-5400 2200);
FORCEPROP 2 LAST SIG_NAME M_F_CPU1_RESET_N
J 0
(-6500 2210);
DISPLAY 0.489362 (-6500 2210);
WIRE 16 -1 (-5900 3300)(-5400 3300);
WIRE 16 -1 (-5900 3700)(-5400 3700);
WIRE 16 -1 (-5900 3350)(-5400 3350);
WIRE 16 -1 (-5900 3750)(-5400 3750);
WIRE 16 -1 (-5900 3400)(-5400 3400);
WIRE 16 -1 (-5900 3800)(-5400 3800);
WIRE 16 -1 (-5900 3450)(-5400 3450);
WIRE 16 -1 (-5900 3850)(-5400 3850);
WIRE 16 -1 (-5900 3500)(-5400 3500);
WIRE 16 -1 (-5900 3900)(-5400 3900);
WIRE 16 -1 (-5900 3550)(-5400 3550);
WIRE 16 -1 (-5900 3950)(-5400 3950);
WIRE 16 -1 (-5900 3600)(-5400 3600);
WIRE 16 -1 (-5900 4000)(-5400 4000);
WIRE 16 -1 (-5700 4200)(-5400 4200);
WIRE 16 -1 (-5700 5000)(-5400 5000);
WIRE 16 -1 (-5900 4550)(-5400 4550);
WIRE 16 -1 (-5700 5100)(-5400 5100);
WIRE 16 -1 (-5900 4650)(-5400 4650);
WIRE 16 -1 (-5900 4750)(-5400 4750);
WIRE 16 -1 (-5900 4850)(-5400 4850);
WIRE 16 -1 (-5900 4950)(-5400 4950);
WIRE 16 -1 (-5900 5050)(-5400 5050);
WIRE 16 -1 (-5700 4300)(-5400 4300);
WIRE 16 -1 (-5700 4400)(-5400 4400);
WIRE 16 -1 (-5700 4500)(-5400 4500);
WIRE 16 -1 (-5700 4600)(-5400 4600);
WIRE 16 -1 (-5900 4150)(-5400 4150);
WIRE 16 -1 (-5700 4700)(-5400 4700);
WIRE 16 -1 (-5900 4250)(-5400 4250);
WIRE 16 -1 (-5700 4800)(-5400 4800);
WIRE 16 -1 (-5900 4350)(-5400 4350);
WIRE 16 -1 (-5700 4900)(-5400 4900);
WIRE 16 -1 (-5900 4450)(-5400 4450);
WIRE 16 -1 (-5700 5450)(-5400 5450);
WIRE 16 -1 (-5700 5550)(-5400 5550);
WIRE 16 -1 (-5700 5650)(-5400 5650);
WIRE 16 -1 (-5900 5200)(-5400 5200);
WIRE 16 -1 (-5700 5750)(-5400 5750);
WIRE 16 -1 (-5900 5300)(-5400 5300);
WIRE 16 -1 (-5700 5850)(-5400 5850);
WIRE 16 -1 (-5900 5400)(-5400 5400);
WIRE 16 -1 (-5700 5950)(-5400 5950);
WIRE 16 -1 (-5900 5500)(-5400 5500);
WIRE 16 -1 (-5700 6050)(-5400 6050);
WIRE 16 -1 (-5900 5600)(-5400 5600);
WIRE 16 -1 (-5900 5700)(-5400 5700);
WIRE 16 -1 (-5900 5800)(-5400 5800);
WIRE 16 -1 (-5900 5900)(-5400 5900);
WIRE 16 -1 (-5900 6000)(-5400 6000);
WIRE 16 -1 (-5900 6100)(-5400 6100);
WIRE 16 -1 (-5700 5250)(-5400 5250);
WIRE 16 -1 (-5700 5350)(-5400 5350);
WIRE 16 -1 (-5700 6150)(-5400 6150);
WIRE 16 -1 (-3800 1750)(-3375 1750);
WIRE 16 -1 (-3800 1800)(-3375 1800);
WIRE 16 -1 (-3800 1850)(-3375 1850);
WIRE 16 -1 (-3800 1900)(-3375 1900);
WIRE 16 -1 (-3800 1950)(-3375 1950);
WIRE 16 -1 (-3800 2000)(-3375 2000);
WIRE 16 -1 (-3800 2750)(-3375 2750);
WIRE 16 -1 (-3800 2800)(-3375 2800);
WIRE 16 -1 (-3800 2850)(-3375 2850);
WIRE 16 -1 (-3800 2900)(-3375 2900);
WIRE 16 -1 (-3800 2950)(-3375 2950);
WIRE 16 -1 (-3800 3000)(-3375 3000);
WIRE 16 -1 (-3800 2200)(-3375 2200);
WIRE 16 -1 (-3800 2050)(-3375 2050);
WIRE 16 -1 (-3800 2250)(-3375 2250);
WIRE 16 -1 (-3800 2100)(-3375 2100);
WIRE 16 -1 (-3800 2650)(-3375 2650);
WIRE 16 -1 (-3800 2300)(-3375 2300);
WIRE 16 -1 (-3800 2700)(-3375 2700);
WIRE 16 -1 (-3800 2350)(-3375 2350);
WIRE 16 -1 (-3800 2400)(-3375 2400);
WIRE 16 -1 (-3800 2450)(-3375 2450);
WIRE 16 -1 (-3800 2500)(-3375 2500);
WIRE 16 -1 (-3800 2550)(-3375 2550);
WIRE 16 -1 (-3800 4050)(-3375 4050);
WIRE 16 -1 (-3800 3350)(-3375 3350);
WIRE 16 -1 (-3800 3400)(-3375 3400);
WIRE 16 -1 (-3800 3450)(-3375 3450);
WIRE 16 -1 (-3800 3550)(-3375 3550);
WIRE 16 -1 (-3800 3600)(-3375 3600);
WIRE 16 -1 (-3800 3650)(-3375 3650);
WIRE 16 -1 (-3800 3700)(-3375 3700);
WIRE 16 -1 (-3800 3100)(-3375 3100);
WIRE 16 -1 (-3800 3750)(-3375 3750);
WIRE 16 -1 (-3800 3150)(-3375 3150);
WIRE 16 -1 (-3800 3800)(-3375 3800);
WIRE 16 -1 (-3800 3200)(-3375 3200);
WIRE 16 -1 (-3800 3250)(-3375 3250);
WIRE 16 -1 (-3800 3850)(-3375 3850);
WIRE 16 -1 (-3800 3900)(-3375 3900);
WIRE 16 -1 (-3800 4000)(-3375 4000);
WIRE 16 -1 (-3800 3300)(-3375 3300);
WIRE 16 -1 (-3800 4100)(-3375 4100);
WIRE 16 -1 (-3800 4150)(-3375 4150);
WIRE 16 -1 (-3800 4200)(-3375 4200);
WIRE 16 -1 (-3800 4250)(-3375 4250);
WIRE 16 -1 (-3800 5100)(-3375 5100);
WIRE 16 -1 (-3800 4300)(-3375 4300);
WIRE 16 -1 (-3800 4550)(-3375 4550);
WIRE 16 -1 (-3800 4350)(-3375 4350);
WIRE 16 -1 (-3800 4600)(-3375 4600);
WIRE 16 -1 (-3800 4650)(-3375 4650);
WIRE 16 -1 (-3800 4700)(-3375 4700);
WIRE 16 -1 (-3800 4750)(-3375 4750);
WIRE 16 -1 (-3800 4800)(-3375 4800);
WIRE 16 -1 (-3800 4900)(-3375 4900);
WIRE 16 -1 (-3800 4950)(-3375 4950);
WIRE 16 -1 (-3800 5000)(-3375 5000);
WIRE 16 -1 (-3800 5050)(-3375 5050);
WIRE 16 -1 (-3800 4450)(-3375 4450);
WIRE 16 -1 (-3800 4500)(-3375 4500);
WIRE 16 -1 (-3800 5800)(-3375 5800);
WIRE 16 -1 (-3800 5850)(-3375 5850);
WIRE 16 -1 (-3800 5900)(-3375 5900);
WIRE 16 -1 (-3800 5950)(-3375 5950);
WIRE 16 -1 (-3800 6000)(-3375 6000);
WIRE 16 -1 (-3800 6050)(-3375 6050);
WIRE 16 -1 (-3800 6100)(-3375 6100);
WIRE 16 -1 (-3800 5150)(-3375 5150);
WIRE 16 -1 (-3800 5200)(-3375 5200);
WIRE 16 -1 (-3800 5250)(-3375 5250);
WIRE 16 -1 (-3800 5350)(-3375 5350);
WIRE 16 -1 (-3800 5400)(-3375 5400);
WIRE 16 -1 (-3800 5450)(-3375 5450);
WIRE 16 -1 (-3800 5500)(-3375 5500);
WIRE 16 -1 (-3800 5550)(-3375 5550);
WIRE 16 -1 (-3800 5600)(-3375 5600);
WIRE 16 -1 (-3800 5650)(-3375 5650);
WIRE 16 -1 (-3800 5700)(-3375 5700);
WIRE 16 -1 (-3800 6150)(-3375 6150);
QUIT
